FILE_TYPE = MACRO_DRAWING;
SET COLOR_WIRE YELLOW;
SET COLOR_PROP ORANGE;
SET COLOR_DOT WHITE;
SET COLOR_ARC YELLOW;
SET COLOR_BODY GREEN;
SET COLOR_NOTE PURPLE;
SET PROP_DISPLAY VALUE;
SET PAGE_NUMBER P137;
FORCEADD OFFPAGE..1
(-7775 -1575);
FORCEPROP 2 LAST $XR1 151 
J 0
(-8147 -1575);
DISPLAY 0.638298 (-8147 -1575);
PAINT MONO (-8147 -1575);
FORCEPROP 2 LAST $XR0 150 
J 0
(-8027 -1575);
DISPLAY 0.638298 (-8027 -1575);
PAINT MONO (-8027 -1575);
FORCEPROP 2 LAST CDS_LIB standard
J 0
(-7775 -1575);
DISPLAY INVISIBLE (-7775 -1575);
FORCEPROP 1 LAST OFFPAGE TRUE
J 0
(-7450 -1700);
DISPLAY 0.872340 (-7450 -1700);
PAINT GREEN (-7450 -1700);
DISPLAY INVISIBLE (-7450 -1700);
FORCEPROP 1 LAST COMMENT_BODY TRUE
J 0
(-7650 -1675);
DISPLAY 0.872340 (-7650 -1675);
PAINT GREEN (-7650 -1675);
DISPLAY INVISIBLE (-7650 -1675);
FORCEPROP 2 LAST PATH I1
J 0
(-7725 -1500);
DISPLAY 0.680851 (-7725 -1500);
DISPLAY INVISIBLE (-7725 -1500);
FORCEADD Q_RES..2
(-6825 -2250);
FORCEPROP 1 LAST LOCATION R200
J 0
(-6780 -2125);
DISPLAY 0.638298 (-6780 -2125);
PAINT SKYBLUE (-6780 -2125);
FORCEPROP 0 LAST $SEC 1
J 0
(-6775 -2075);
DISPLAY 0.680851 (-6775 -2075);
PAINT MONO (-6775 -2075);
DISPLAY INVISIBLE (-6775 -2075);
FORCEPROP 0 LAST CDS_SEC 1
J 0
(-6775 -2075);
DISPLAY 0.680851 (-6775 -2075);
DISPLAY INVISIBLE (-6775 -2075);
FORCEPROP 1 LASTPIN (-6825 -2150) $PN 1
J 0
(-6820 -2188);
DISPLAY 0.787234 (-6820 -2188);
PAINT MONO (-6820 -2188);
FORCEPROP 1 LASTPIN (-6825 -2350) $PN 2
J 0
(-6820 -2340);
DISPLAY 0.787234 (-6820 -2340);
PAINT MONO (-6820 -2340);
FORCEPROP 1 LAST TOLERANCE 5%
J 0
(-6780 -2225);
DISPLAY 0.489362 (-6780 -2225);
PAINT SKYBLUE (-6780 -2225);
FORCEPROP 1 LAST MATERIAL EMPTY
J 0
(-6785 -2325);
DISPLAY 0.489362 (-6785 -2325);
PAINT RED (-6785 -2325);
FORCEPROP 1 LAST PACK_TYPE 0402LF
J 0
(-6775 -2375);
DISPLAY 0.489362 (-6775 -2375);
PAINT SKYBLUE (-6775 -2375);
FORCEPROP 1 LAST WATTAGE 1/16W
J 0
(-6785 -2275);
DISPLAY 0.489362 (-6785 -2275);
PAINT SKYBLUE (-6785 -2275);
FORCEPROP 1 LAST VALUE 4.7K
J 0
(-6780 -2175);
DISPLAY 0.489362 (-6780 -2175);
PAINT SKYBLUE (-6780 -2175);
FORCEPROP 2 LAST CDS_LIB pure_quanta
J 0
(-6825 -2250);
DISPLAY INVISIBLE (-6825 -2250);
FORCEPROP 1 LAST PATH I13
J 0
(-6775 -2075);
DISPLAY 0.978723 (-6775 -2075);
PAINT WHITE (-6775 -2075);
DISPLAY INVISIBLE (-6775 -2075);
FORCEPROP 1 LAST PART_NUMBER CS24702JB10
J 0
(-6785 -2375);
DISPLAY 0.489362 (-6785 -2375);
PAINT SKYBLUE (-6785 -2375);
DISPLAY INVISIBLE (-6785 -2375);
FORCEADD Q_RES..1
(-3900 -1675);
FORCEPROP 1 LAST LOCATION R1154
J 0
(-4100 -1675);
DISPLAY 0.489362 (-4100 -1675);
PAINT SKYBLUE (-4100 -1675);
FORCEPROP 0 LAST $SEC 1
J 0
(-4025 -1625);
DISPLAY 0.680851 (-4025 -1625);
PAINT MONO (-4025 -1625);
DISPLAY INVISIBLE (-4025 -1625);
FORCEPROP 0 LAST CDS_SEC 1
J 0
(-4025 -1625);
DISPLAY 1.021277 (-4025 -1625);
DISPLAY INVISIBLE (-4025 -1625);
FORCEPROP 1 LASTPIN (-4000 -1675) $PN 1
J 0
(-3988 -1663);
DISPLAY 0.489362 (-3988 -1663);
PAINT MONO (-3988 -1663);
FORCEPROP 1 LASTPIN (-3800 -1675) $PN 2
J 0
(-3838 -1663);
DISPLAY 0.489362 (-3838 -1663);
PAINT MONO (-3838 -1663);
FORCEPROP 1 LAST VALUE 0
J 2
(-3700 -1675);
DISPLAY 0.489362 (-3700 -1675);
PAINT SKYBLUE (-3700 -1675);
FORCEPROP 2 LAST CDS_LIB pure_quanta
J 0
(-3900 -1675);
DISPLAY INVISIBLE (-3900 -1675);
FORCEPROP 1 LAST WATTAGE 1/16W
J 2
(-3500 -1750);
DISPLAY 0.489362 (-3500 -1750);
PAINT SKYBLUE (-3500 -1750);
DISPLAY INVISIBLE (-3500 -1750);
FORCEPROP 1 LAST MATERIAL CHIP
J 0
(-3475 -1750);
DISPLAY 0.489362 (-3475 -1750);
PAINT SKYBLUE (-3475 -1750);
DISPLAY INVISIBLE (-3475 -1750);
FORCEPROP 1 LAST TOLERANCE 5%
J 0
(-3925 -1750);
DISPLAY 0.489362 (-3925 -1750);
PAINT SKYBLUE (-3925 -1750);
DISPLAY INVISIBLE (-3925 -1750);
FORCEPROP 1 LAST PACK_TYPE 0402LF
J 0
(-3850 -1750);
DISPLAY 0.489362 (-3850 -1750);
PAINT SKYBLUE (-3850 -1750);
DISPLAY INVISIBLE (-3850 -1750);
FORCEPROP 1 LAST PATH I15
J 0
(-3950 -1525);
DISPLAY 0.978723 (-3950 -1525);
PAINT WHITE (-3950 -1525);
DISPLAY INVISIBLE (-3950 -1525);
FORCEPROP 1 LAST PART_NUMBER CS00002JB13
J 0
(-3875 -1625);
DISPLAY 0.489362 (-3875 -1625);
PAINT SKYBLUE (-3875 -1625);
DISPLAY INVISIBLE (-3875 -1625);
FORCEADD Q_RES..1
(-3900 -1575);
FORCEPROP 1 LAST LOCATION R1153
J 0
(-4100 -1575);
DISPLAY 0.489362 (-4100 -1575);
PAINT SKYBLUE (-4100 -1575);
FORCEPROP 0 LAST $SEC 1
J 0
(-4025 -1525);
DISPLAY 0.680851 (-4025 -1525);
PAINT MONO (-4025 -1525);
DISPLAY INVISIBLE (-4025 -1525);
FORCEPROP 0 LAST CDS_SEC 1
J 0
(-4025 -1525);
DISPLAY 1.021277 (-4025 -1525);
DISPLAY INVISIBLE (-4025 -1525);
FORCEPROP 1 LASTPIN (-4000 -1575) $PN 1
J 0
(-3988 -1563);
DISPLAY 0.489362 (-3988 -1563);
PAINT MONO (-3988 -1563);
FORCEPROP 1 LASTPIN (-3800 -1575) $PN 2
J 0
(-3838 -1563);
DISPLAY 0.489362 (-3838 -1563);
PAINT MONO (-3838 -1563);
FORCEPROP 1 LAST VALUE 0
J 2
(-3700 -1575);
DISPLAY 0.489362 (-3700 -1575);
PAINT SKYBLUE (-3700 -1575);
FORCEPROP 2 LAST CDS_LIB pure_quanta
J 0
(-3900 -1575);
DISPLAY INVISIBLE (-3900 -1575);
FORCEPROP 1 LAST WATTAGE 1/16W
J 2
(-3500 -1650);
DISPLAY 0.489362 (-3500 -1650);
PAINT SKYBLUE (-3500 -1650);
DISPLAY INVISIBLE (-3500 -1650);
FORCEPROP 1 LAST MATERIAL CHIP
J 0
(-3475 -1650);
DISPLAY 0.489362 (-3475 -1650);
PAINT SKYBLUE (-3475 -1650);
DISPLAY INVISIBLE (-3475 -1650);
FORCEPROP 1 LAST TOLERANCE 5%
J 0
(-3925 -1650);
DISPLAY 0.489362 (-3925 -1650);
PAINT SKYBLUE (-3925 -1650);
DISPLAY INVISIBLE (-3925 -1650);
FORCEPROP 1 LAST PACK_TYPE 0402LF
J 0
(-3850 -1650);
DISPLAY 0.489362 (-3850 -1650);
PAINT SKYBLUE (-3850 -1650);
DISPLAY INVISIBLE (-3850 -1650);
FORCEPROP 1 LAST PATH I16
J 0
(-3950 -1425);
DISPLAY 0.978723 (-3950 -1425);
PAINT WHITE (-3950 -1425);
DISPLAY INVISIBLE (-3950 -1425);
FORCEPROP 1 LAST PART_NUMBER CS00002JB13
J 0
(-3875 -1525);
DISPLAY 0.489362 (-3875 -1525);
PAINT SKYBLUE (-3875 -1525);
DISPLAY INVISIBLE (-3875 -1525);
FORCEADD OFFPAGE..3
(-2925 -1675);
FORCEPROP 2 LAST $XR1 161 
J 0
(-2591 -1675);
DISPLAY 0.638298 (-2591 -1675);
PAINT MONO (-2591 -1675);
FORCEPROP 2 LAST $XR0 160 
J 0
(-2711 -1675);
DISPLAY 0.638298 (-2711 -1675);
PAINT MONO (-2711 -1675);
FORCEPROP 2 LAST CDS_LIB standard
J 0
(-2925 -1675);
DISPLAY INVISIBLE (-2925 -1675);
FORCEPROP 1 LAST OFFPAGE TRUE
J 0
(-2600 -1800);
DISPLAY 0.872340 (-2600 -1800);
PAINT GREEN (-2600 -1800);
DISPLAY INVISIBLE (-2600 -1800);
FORCEPROP 1 LAST COMMENT_BODY TRUE
J 0
(-2975 -1775);
DISPLAY 0.872340 (-2975 -1775);
PAINT PEACH (-2975 -1775);
DISPLAY INVISIBLE (-2975 -1775);
FORCEPROP 2 LAST PATH I17
J 0
(-2575 -1625);
DISPLAY 0.680851 (-2575 -1625);
DISPLAY INVISIBLE (-2575 -1625);
FORCEADD OFFPAGE..2
(-2900 -1575);
FORCEPROP 2 LAST $XR1 161 
J 0
(-2591 -1575);
DISPLAY 0.638298 (-2591 -1575);
PAINT MONO (-2591 -1575);
FORCEPROP 2 LAST $XR0 160 
J 0
(-2711 -1575);
DISPLAY 0.638298 (-2711 -1575);
PAINT MONO (-2711 -1575);
FORCEPROP 2 LAST CDS_LIB standard
J 0
(-2900 -1575);
DISPLAY INVISIBLE (-2900 -1575);
FORCEPROP 1 LAST OFFPAGE TRUE
J 0
(-2575 -1700);
DISPLAY 0.872340 (-2575 -1700);
PAINT GREEN (-2575 -1700);
DISPLAY INVISIBLE (-2575 -1700);
FORCEPROP 1 LAST COMMENT_BODY TRUE
J 0
(-2945 -1670);
DISPLAY 0.872340 (-2945 -1670);
PAINT GREEN (-2945 -1670);
DISPLAY INVISIBLE (-2945 -1670);
FORCEPROP 2 LAST PATH I18
J 0
(-2575 -1525);
DISPLAY 0.680851 (-2575 -1525);
DISPLAY INVISIBLE (-2575 -1525);
FORCEADD OFFPAGE..5
(-2475 -600);
FORCEPROP 2 LAST $XR1 161 
J 0
(-2850 -600);
DISPLAY 0.638298 (-2850 -600);
PAINT MONO (-2850 -600);
FORCEPROP 2 LAST $XR0 160 
J 0
(-2730 -600);
DISPLAY 0.638298 (-2730 -600);
PAINT MONO (-2730 -600);
FORCEPROP 2 LAST CDS_LIB standard
J 0
(-2475 -600);
DISPLAY INVISIBLE (-2475 -600);
FORCEPROP 1 LAST OFFPAGE TRUE
J 0
(-2150 -725);
DISPLAY 0.872340 (-2150 -725);
PAINT GREEN (-2150 -725);
DISPLAY INVISIBLE (-2150 -725);
FORCEPROP 1 LAST COMMENT_BODY TRUE
J 0
(-2375 -675);
DISPLAY 0.872340 (-2375 -675);
PAINT GREEN (-2375 -675);
DISPLAY INVISIBLE (-2375 -675);
FORCEPROP 2 LAST PATH I19
J 0
(-2425 -525);
DISPLAY 0.680851 (-2425 -525);
DISPLAY INVISIBLE (-2425 -525);
FORCEADD OFFPAGE..3
R 2
(-7725 -1675);
FORCEPROP 2 LAST $XR1 151 
J 0
(-8125 -1675);
DISPLAY 0.638298 (-8125 -1675);
PAINT MONO (-8125 -1675);
FORCEPROP 2 LAST $XR0 150 
J 0
(-8005 -1675);
DISPLAY 0.638298 (-8005 -1675);
PAINT MONO (-8005 -1675);
FORCEPROP 2 LAST CDS_LIB standard
J 0
(-7725 -1675);
DISPLAY INVISIBLE (-7725 -1675);
FORCEPROP 1 LAST OFFPAGE TRUE
J 2
(-8050 -1800);
DISPLAY 0.872340 (-8050 -1800);
PAINT GREEN (-8050 -1800);
DISPLAY INVISIBLE (-8050 -1800);
FORCEPROP 1 LAST COMMENT_BODY TRUE
J 2
(-7675 -1775);
DISPLAY 0.872340 (-7675 -1775);
PAINT GREEN (-7675 -1775);
DISPLAY INVISIBLE (-7675 -1775);
FORCEPROP 2 LAST PATH I2
J 0
(-7675 -1600);
DISPLAY 0.680851 (-7675 -1600);
DISPLAY INVISIBLE (-7675 -1600);
FORCEADD OFFPAGE..5
(-2475 -550);
FORCEPROP 2 LAST $XR1 161 
J 0
(-2850 -550);
DISPLAY 0.638298 (-2850 -550);
PAINT MONO (-2850 -550);
FORCEPROP 2 LAST $XR0 160 
J 0
(-2730 -550);
DISPLAY 0.638298 (-2730 -550);
PAINT MONO (-2730 -550);
FORCEPROP 2 LAST CDS_LIB standard
J 0
(-2475 -550);
DISPLAY INVISIBLE (-2475 -550);
FORCEPROP 1 LAST OFFPAGE TRUE
J 0
(-2150 -675);
DISPLAY 0.872340 (-2150 -675);
PAINT GREEN (-2150 -675);
DISPLAY INVISIBLE (-2150 -675);
FORCEPROP 1 LAST COMMENT_BODY TRUE
J 0
(-2375 -625);
DISPLAY 0.872340 (-2375 -625);
PAINT GREEN (-2375 -625);
DISPLAY INVISIBLE (-2375 -625);
FORCEPROP 2 LAST PATH I20
J 0
(-2425 -475);
DISPLAY 0.680851 (-2425 -475);
DISPLAY INVISIBLE (-2425 -475);
FORCEADD OFFPAGE..5
(-2475 -500);
FORCEPROP 2 LAST $XR0 160 
J 0
(-2730 -500);
DISPLAY 0.638298 (-2730 -500);
PAINT MONO (-2730 -500);
FORCEPROP 2 LAST CDS_LIB standard
J 0
(-2475 -500);
DISPLAY INVISIBLE (-2475 -500);
FORCEPROP 1 LAST OFFPAGE TRUE
J 0
(-2150 -625);
DISPLAY 0.872340 (-2150 -625);
PAINT GREEN (-2150 -625);
DISPLAY INVISIBLE (-2150 -625);
FORCEPROP 1 LAST COMMENT_BODY TRUE
J 0
(-2375 -575);
DISPLAY 0.872340 (-2375 -575);
PAINT GREEN (-2375 -575);
DISPLAY INVISIBLE (-2375 -575);
FORCEPROP 2 LAST PATH I21
J 0
(-2425 -425);
DISPLAY 0.680851 (-2425 -425);
DISPLAY INVISIBLE (-2425 -425);
FORCEADD UNIVERSAL_GND..1
(-6500 1925);
FORCEPROP 3 LASTPIN (-6500 1975) SIG_NAME GND\g
J 0
(-6490 1985);
DISPLAY 0.659574 (-6490 1985);
PAINT MONO (-6490 1985);
DISPLAY INVISIBLE (-6490 1985);
FORCEPROP 2 LAST CDS_LIB pure_quanta_power
J 0
(-6500 1925);
DISPLAY INVISIBLE (-6500 1925);
FORCEPROP 1 LAST HDL_POWER GND
J 1
(-6475 1850);
DISPLAY 0.872340 (-6475 1850);
PAINT GREEN (-6475 1850);
DISPLAY INVISIBLE (-6475 1850);
FORCEPROP 1 LAST PATH I24
J 0
(-6425 1925);
DISPLAY 0.872340 (-6425 1925);
PAINT AQUA (-6425 1925);
DISPLAY INVISIBLE (-6425 1925);
FORCEADD UNIVERSAL_GND..1
(-6650 2550);
FORCEPROP 3 LASTPIN (-6650 2600) SIG_NAME GND\g
J 0
(-6640 2610);
DISPLAY 0.659574 (-6640 2610);
PAINT MONO (-6640 2610);
DISPLAY INVISIBLE (-6640 2610);
FORCEPROP 2 LAST CDS_LIB pure_quanta_power
J 0
(-6650 2550);
DISPLAY INVISIBLE (-6650 2550);
FORCEPROP 1 LAST HDL_POWER GND
J 1
(-6625 2475);
DISPLAY 0.872340 (-6625 2475);
PAINT GREEN (-6625 2475);
DISPLAY INVISIBLE (-6625 2475);
FORCEPROP 1 LAST PATH I25
J 0
(-6575 2550);
DISPLAY 0.872340 (-6575 2550);
PAINT AQUA (-6575 2550);
DISPLAY INVISIBLE (-6575 2550);
FORCEADD Q_CAP..1
(-6650 2750);
FORCEPROP 1 LAST LOCATION C23
J 2
(-6700 2900);
DISPLAY 0.489362 (-6700 2900);
PAINT SKYBLUE (-6700 2900);
FORCEPROP 0 LAST $SEC 1
J 0
(-6700 2950);
DISPLAY 0.680851 (-6700 2950);
PAINT MONO (-6700 2950);
DISPLAY INVISIBLE (-6700 2950);
FORCEPROP 0 LAST CDS_SEC 1
J 0
(-6700 2950);
DISPLAY 1.021277 (-6700 2950);
DISPLAY INVISIBLE (-6700 2950);
FORCEPROP 1 LASTPIN (-6650 2850) $PN 1
J 0
(-6640 2830);
DISPLAY 0.489362 (-6640 2830);
PAINT MONO (-6640 2830);
FORCEPROP 1 LASTPIN (-6650 2650) $PN 2
J 0
(-6640 2630);
DISPLAY 0.489362 (-6640 2630);
PAINT MONO (-6640 2630);
FORCEPROP 1 LAST TOLERANCE 10%
J 2
(-6700 2750);
DISPLAY 0.489362 (-6700 2750);
PAINT SKYBLUE (-6700 2750);
FORCEPROP 1 LAST VOLTAGE 25V
J 2
(-6700 2800);
DISPLAY 0.489362 (-6700 2800);
PAINT SKYBLUE (-6700 2800);
FORCEPROP 1 LAST MATERIAL X7R
J 2
(-6700 2700);
DISPLAY 0.489362 (-6700 2700);
PAINT SKYBLUE (-6700 2700);
FORCEPROP 1 LAST PACK_TYPE 0402
J 2
(-6700 2650);
DISPLAY 0.489362 (-6700 2650);
PAINT SKYBLUE (-6700 2650);
FORCEPROP 1 LAST VALUE 0.1UF
J 2
(-6700 2850);
DISPLAY 0.489362 (-6700 2850);
PAINT SKYBLUE (-6700 2850);
FORCEPROP 2 LAST CDS_LIB pure_quanta
J 0
(-6650 2750);
DISPLAY INVISIBLE (-6650 2750);
FORCEPROP 1 LAST PATH I26
J 0
(-6600 2900);
DISPLAY 0.978723 (-6600 2900);
PAINT WHITE (-6600 2900);
DISPLAY INVISIBLE (-6600 2900);
FORCEPROP 1 LAST PART_NUMBER CH4104K1B00
J 0
(-6600 2600);
DISPLAY 0.489362 (-6600 2600);
PAINT SKYBLUE (-6600 2600);
DISPLAY INVISIBLE (-6600 2600);
FORCEADD UNIVERSAL_POWER..1
R 2
(-6475 3025);
FORCEPROP 3 LASTPIN (-6475 2975) SIG_NAME P3V3_AUX\g
J 0
(-6465 2985);
DISPLAY 0.659574 (-6465 2985);
PAINT MONO (-6465 2985);
DISPLAY INVISIBLE (-6465 2985);
FORCEPROP 1 LAST HDL_POWER P3V3_AUX
J 1
(-6475 3075);
DISPLAY 0.489362 (-6475 3075);
PAINT GREEN (-6475 3075);
FORCEPROP 2 LAST CDS_LIB pure_quanta_power
J 0
(-6475 3025);
DISPLAY INVISIBLE (-6475 3025);
FORCEPROP 1 LAST PATH I27
J 2
(-6525 3050);
DISPLAY 0.872340 (-6525 3050);
PAINT AQUA (-6525 3050);
DISPLAY INVISIBLE (-6525 3050);
FORCEADD UNIVERSAL_GND..1
(-5325 2550);
FORCEPROP 3 LASTPIN (-5325 2600) SIG_NAME GND\g
J 0
(-5315 2610);
DISPLAY 0.659574 (-5315 2610);
PAINT MONO (-5315 2610);
DISPLAY INVISIBLE (-5315 2610);
FORCEPROP 2 LAST CDS_LIB pure_quanta_power
J 0
(-5325 2550);
DISPLAY INVISIBLE (-5325 2550);
FORCEPROP 1 LAST HDL_POWER GND
J 1
(-5300 2475);
DISPLAY 0.872340 (-5300 2475);
PAINT GREEN (-5300 2475);
DISPLAY INVISIBLE (-5300 2475);
FORCEPROP 1 LAST PATH I28
J 0
(-5250 2550);
DISPLAY 0.872340 (-5250 2550);
PAINT AQUA (-5250 2550);
DISPLAY INVISIBLE (-5250 2550);
FORCEADD Q_CAP..1
(-5325 2750);
FORCEPROP 1 LAST LOCATION C26
J 0
(-5275 2875);
DISPLAY 0.489362 (-5275 2875);
PAINT SKYBLUE (-5275 2875);
FORCEPROP 0 LAST $SEC 1
J 0
(-5275 2950);
DISPLAY 0.680851 (-5275 2950);
PAINT MONO (-5275 2950);
DISPLAY INVISIBLE (-5275 2950);
FORCEPROP 0 LAST CDS_SEC 1
J 0
(-5275 2950);
DISPLAY 1.021277 (-5275 2950);
DISPLAY INVISIBLE (-5275 2950);
FORCEPROP 1 LASTPIN (-5325 2850) $PN 1
J 0
(-5315 2830);
DISPLAY 0.489362 (-5315 2830);
PAINT MONO (-5315 2830);
FORCEPROP 1 LASTPIN (-5325 2650) $PN 2
J 0
(-5315 2630);
DISPLAY 0.489362 (-5315 2630);
PAINT MONO (-5315 2630);
FORCEPROP 1 LAST PACK_TYPE 0402
J 0
(-5275 2650);
DISPLAY 0.489362 (-5275 2650);
PAINT SKYBLUE (-5275 2650);
FORCEPROP 1 LAST MATERIAL X7R
J 0
(-5275 2700);
DISPLAY 0.489362 (-5275 2700);
PAINT SKYBLUE (-5275 2700);
FORCEPROP 1 LAST TOLERANCE 10%
J 0
(-5275 2750);
DISPLAY 0.489362 (-5275 2750);
PAINT SKYBLUE (-5275 2750);
FORCEPROP 1 LAST VOLTAGE 25V
J 0
(-5275 2800);
DISPLAY 0.489362 (-5275 2800);
PAINT SKYBLUE (-5275 2800);
FORCEPROP 1 LAST VALUE 0.1UF
J 0
(-5275 2850);
DISPLAY 0.489362 (-5275 2850);
PAINT SKYBLUE (-5275 2850);
FORCEPROP 2 LAST CDS_LIB pure_quanta
J 0
(-5325 2750);
DISPLAY INVISIBLE (-5325 2750);
FORCEPROP 1 LAST PATH I29
J 0
(-5275 2900);
DISPLAY 0.978723 (-5275 2900);
PAINT WHITE (-5275 2900);
DISPLAY INVISIBLE (-5275 2900);
FORCEPROP 1 LAST PART_NUMBER CH4104K1B00
J 0
(-5275 2600);
DISPLAY 0.489362 (-5275 2600);
PAINT SKYBLUE (-5275 2600);
DISPLAY INVISIBLE (-5275 2600);
FORCEADD UNIVERSAL_GND..1
(-5050 -2075);
FORCEPROP 3 LASTPIN (-5050 -2025) SIG_NAME GND\g
J 0
(-5040 -2015);
DISPLAY 0.659574 (-5040 -2015);
PAINT MONO (-5040 -2015);
DISPLAY INVISIBLE (-5040 -2015);
FORCEPROP 2 LAST CDS_LIB pure_quanta_power
J 0
(-5050 -2075);
DISPLAY INVISIBLE (-5050 -2075);
FORCEPROP 1 LAST HDL_POWER GND
J 1
(-5025 -2150);
DISPLAY 0.872340 (-5025 -2150);
PAINT GREEN (-5025 -2150);
DISPLAY INVISIBLE (-5025 -2150);
FORCEPROP 1 LAST PATH I3
J 0
(-4975 -2075);
DISPLAY 0.872340 (-4975 -2075);
PAINT AQUA (-4975 -2075);
DISPLAY INVISIBLE (-4975 -2075);
FORCEADD VCC_CORE..1
(-5400 3000);
FORCEPROP 3 LASTPIN (-5400 2950) SIG_NAME P3V3\g
J 0
(-5390 2960);
DISPLAY 0.659574 (-5390 2960);
PAINT MONO (-5390 2960);
DISPLAY INVISIBLE (-5390 2960);
FORCEPROP 1 LAST HDL_POWER P3V3
J 1
(-5400 3050);
DISPLAY 0.489362 (-5400 3050);
PAINT GREEN (-5400 3050);
FORCEPROP 2 LAST CDS_LIB pure_quanta_power
J 0
(-5400 3000);
DISPLAY INVISIBLE (-5400 3000);
FORCEPROP 1 LAST PATH I30
J 0
(-5350 3025);
DISPLAY 0.872340 (-5350 3025);
PAINT AQUA (-5350 3025);
DISPLAY INVISIBLE (-5350 3025);
FORCEADD Q_RES..2
(-4225 1775);
FORCEPROP 1 LAST LOCATION R78
J 0
(-4180 1900);
DISPLAY 0.489362 (-4180 1900);
PAINT SKYBLUE (-4180 1900);
FORCEPROP 0 LAST $SEC 1
J 0
(-4175 1925);
DISPLAY 0.680851 (-4175 1925);
PAINT MONO (-4175 1925);
DISPLAY INVISIBLE (-4175 1925);
FORCEPROP 0 LAST CDS_SEC 1
J 0
(-4175 1925);
DISPLAY 0.680851 (-4175 1925);
DISPLAY INVISIBLE (-4175 1925);
FORCEPROP 1 LASTPIN (-4225 1875) $PN 1
J 0
(-4220 1837);
DISPLAY 0.787234 (-4220 1837);
PAINT MONO (-4220 1837);
FORCEPROP 1 LASTPIN (-4225 1675) $PN 2
J 0
(-4220 1685);
DISPLAY 0.787234 (-4220 1685);
PAINT MONO (-4220 1685);
FORCEPROP 1 LAST TOLERANCE 5%
J 0
(-4180 1800);
DISPLAY 0.489362 (-4180 1800);
PAINT SKYBLUE (-4180 1800);
FORCEPROP 1 LAST VALUE 4.7K
J 0
(-4180 1850);
DISPLAY 0.489362 (-4180 1850);
PAINT SKYBLUE (-4180 1850);
FORCEPROP 1 LAST WATTAGE 1/16W
J 0
(-4185 1750);
DISPLAY 0.489362 (-4185 1750);
PAINT SKYBLUE (-4185 1750);
FORCEPROP 1 LAST MATERIAL EMPTY
J 0
(-4185 1700);
DISPLAY 0.489362 (-4185 1700);
PAINT RED (-4185 1700);
FORCEPROP 1 LAST PACK_TYPE 0402LF
J 0
(-4175 1650);
DISPLAY 0.489362 (-4175 1650);
PAINT SKYBLUE (-4175 1650);
FORCEPROP 2 LAST CDS_LIB pure_quanta
J 0
(-4225 1775);
DISPLAY INVISIBLE (-4225 1775);
FORCEPROP 1 LAST PATH I31
J 0
(-4175 1950);
DISPLAY 0.978723 (-4175 1950);
PAINT WHITE (-4175 1950);
DISPLAY INVISIBLE (-4175 1950);
FORCEPROP 1 LAST PART_NUMBER CS24702JB10
J 0
(-4185 1650);
DISPLAY 0.489362 (-4185 1650);
PAINT SKYBLUE (-4185 1650);
DISPLAY INVISIBLE (-4185 1650);
FORCEADD VCC_CORE..1
(-4225 2050);
FORCEPROP 3 LASTPIN (-4225 2000) SIG_NAME P3V3\g
J 0
(-4215 2010);
DISPLAY 0.659574 (-4215 2010);
PAINT MONO (-4215 2010);
DISPLAY INVISIBLE (-4215 2010);
FORCEPROP 1 LAST HDL_POWER P3V3
J 1
(-4225 2100);
DISPLAY 0.489362 (-4225 2100);
PAINT GREEN (-4225 2100);
FORCEPROP 2 LAST CDS_LIB pure_quanta_power
J 0
(-4225 2050);
DISPLAY INVISIBLE (-4225 2050);
FORCEPROP 1 LAST PATH I32
J 0
(-4175 2075);
DISPLAY 0.872340 (-4175 2075);
PAINT AQUA (-4175 2075);
DISPLAY INVISIBLE (-4175 2075);
FORCEADD OFFPAGE..5
(-2475 -450);
FORCEPROP 2 LAST $XR0 160 
J 0
(-2730 -450);
DISPLAY 0.638298 (-2730 -450);
PAINT MONO (-2730 -450);
FORCEPROP 2 LAST CDS_LIB standard
J 0
(-2475 -450);
DISPLAY INVISIBLE (-2475 -450);
FORCEPROP 1 LAST OFFPAGE TRUE
J 0
(-2150 -575);
DISPLAY 0.872340 (-2150 -575);
PAINT GREEN (-2150 -575);
DISPLAY INVISIBLE (-2150 -575);
FORCEPROP 1 LAST COMMENT_BODY TRUE
J 0
(-2375 -525);
DISPLAY 0.872340 (-2375 -525);
PAINT GREEN (-2375 -525);
DISPLAY INVISIBLE (-2375 -525);
FORCEPROP 2 LAST PATH I37
J 0
(-2425 -375);
DISPLAY 0.680851 (-2425 -375);
DISPLAY INVISIBLE (-2425 -375);
FORCEADD Q_RES..2
(-1550 -150);
FORCEPROP 1 LAST LOCATION R361
J 0
(-1505 -25);
DISPLAY 0.489362 (-1505 -25);
PAINT SKYBLUE (-1505 -25);
FORCEPROP 0 LAST $SEC 1
J 0
(-1500 25);
DISPLAY 0.680851 (-1500 25);
PAINT MONO (-1500 25);
DISPLAY INVISIBLE (-1500 25);
FORCEPROP 0 LAST CDS_SEC 1
J 0
(-1500 25);
DISPLAY 1.021277 (-1500 25);
DISPLAY INVISIBLE (-1500 25);
FORCEPROP 1 LASTPIN (-1550 -50) $PN 1
J 0
(-1545 -88);
DISPLAY 0.489362 (-1545 -88);
PAINT MONO (-1545 -88);
FORCEPROP 1 LASTPIN (-1550 -250) $PN 2
J 0
(-1545 -240);
DISPLAY 0.489362 (-1545 -240);
PAINT MONO (-1545 -240);
FORCEPROP 1 LAST VALUE 4.7K
J 0
(-1505 -75);
DISPLAY 0.489362 (-1505 -75);
PAINT SKYBLUE (-1505 -75);
FORCEPROP 1 LAST TOLERANCE 5%
J 0
(-1505 -125);
DISPLAY 0.489362 (-1505 -125);
PAINT SKYBLUE (-1505 -125);
FORCEPROP 1 LAST PACK_TYPE 0402LF
J 0
(-1500 -275);
DISPLAY 0.489362 (-1500 -275);
PAINT SKYBLUE (-1500 -275);
FORCEPROP 1 LAST MATERIAL EMPTY
J 0
(-1510 -225);
DISPLAY 0.489362 (-1510 -225);
PAINT RED (-1510 -225);
FORCEPROP 1 LAST WATTAGE 1/16W
J 0
(-1510 -175);
DISPLAY 0.489362 (-1510 -175);
PAINT SKYBLUE (-1510 -175);
FORCEPROP 2 LAST CDS_LIB pure_quanta
J 0
(-1550 -150);
DISPLAY INVISIBLE (-1550 -150);
FORCEPROP 1 LAST PATH I40
J 0
(-1500 25);
DISPLAY 0.978723 (-1500 25);
PAINT WHITE (-1500 25);
DISPLAY INVISIBLE (-1500 25);
FORCEPROP 1 LAST PART_NUMBER CS24702JB10
J 0
(-1510 -275);
DISPLAY 0.489362 (-1510 -275);
PAINT SKYBLUE (-1510 -275);
DISPLAY INVISIBLE (-1510 -275);
FORCEADD Q_RES..2
(-1225 -150);
FORCEPROP 1 LAST LOCATION R365
J 0
(-1180 -25);
DISPLAY 0.489362 (-1180 -25);
PAINT SKYBLUE (-1180 -25);
FORCEPROP 0 LAST $SEC 1
J 0
(-1175 25);
DISPLAY 0.680851 (-1175 25);
PAINT MONO (-1175 25);
DISPLAY INVISIBLE (-1175 25);
FORCEPROP 0 LAST CDS_SEC 1
J 0
(-1175 25);
DISPLAY 1.021277 (-1175 25);
DISPLAY INVISIBLE (-1175 25);
FORCEPROP 1 LASTPIN (-1225 -50) $PN 1
J 0
(-1220 -88);
DISPLAY 0.489362 (-1220 -88);
PAINT MONO (-1220 -88);
FORCEPROP 1 LASTPIN (-1225 -250) $PN 2
J 0
(-1220 -240);
DISPLAY 0.489362 (-1220 -240);
PAINT MONO (-1220 -240);
FORCEPROP 1 LAST WATTAGE 1/16W
J 0
(-1185 -175);
DISPLAY 0.489362 (-1185 -175);
PAINT SKYBLUE (-1185 -175);
FORCEPROP 1 LAST MATERIAL EMPTY
J 0
(-1185 -225);
DISPLAY 0.489362 (-1185 -225);
PAINT RED (-1185 -225);
FORCEPROP 1 LAST PACK_TYPE 0402LF
J 0
(-1175 -275);
DISPLAY 0.489362 (-1175 -275);
PAINT SKYBLUE (-1175 -275);
FORCEPROP 1 LAST VALUE 4.7K
J 0
(-1180 -75);
DISPLAY 0.489362 (-1180 -75);
PAINT SKYBLUE (-1180 -75);
FORCEPROP 1 LAST TOLERANCE 5%
J 0
(-1180 -125);
DISPLAY 0.489362 (-1180 -125);
PAINT SKYBLUE (-1180 -125);
FORCEPROP 2 LAST CDS_LIB pure_quanta
J 0
(-1225 -150);
DISPLAY INVISIBLE (-1225 -150);
FORCEPROP 1 LAST PATH I41
J 0
(-1175 25);
DISPLAY 0.978723 (-1175 25);
PAINT WHITE (-1175 25);
DISPLAY INVISIBLE (-1175 25);
FORCEPROP 1 LAST PART_NUMBER CS24702JB10
J 0
(-1185 -275);
DISPLAY 0.489362 (-1185 -275);
PAINT SKYBLUE (-1185 -275);
DISPLAY INVISIBLE (-1185 -275);
FORCEADD VCC_CORE..1
(-1550 100);
FORCEPROP 3 LASTPIN (-1550 50) SIG_NAME P3V3\g
J 0
(-1540 60);
DISPLAY 0.659574 (-1540 60);
PAINT MONO (-1540 60);
DISPLAY INVISIBLE (-1540 60);
FORCEPROP 1 LAST HDL_POWER P3V3
J 1
(-1550 150);
DISPLAY 0.489362 (-1550 150);
PAINT GREEN (-1550 150);
FORCEPROP 2 LAST CDS_LIB pure_quanta_power
J 0
(-1550 100);
DISPLAY INVISIBLE (-1550 100);
FORCEPROP 1 LAST PATH I42
J 0
(-1500 125);
DISPLAY 0.872340 (-1500 125);
PAINT AQUA (-1500 125);
DISPLAY INVISIBLE (-1500 125);
FORCEADD VCC_CORE..1
(-1225 100);
FORCEPROP 3 LASTPIN (-1225 50) SIG_NAME P3V3\g
J 0
(-1215 60);
DISPLAY 0.659574 (-1215 60);
PAINT MONO (-1215 60);
DISPLAY INVISIBLE (-1215 60);
FORCEPROP 1 LAST HDL_POWER P3V3
J 1
(-1225 150);
DISPLAY 0.489362 (-1225 150);
PAINT GREEN (-1225 150);
FORCEPROP 2 LAST CDS_LIB pure_quanta_power
J 0
(-1225 100);
DISPLAY INVISIBLE (-1225 100);
FORCEPROP 1 LAST PATH I43
J 0
(-1175 125);
DISPLAY 0.872340 (-1175 125);
PAINT AQUA (-1175 125);
DISPLAY INVISIBLE (-1175 125);
FORCEADD Q_RES..2
(-925 -150);
FORCEPROP 1 LAST LOCATION R368
J 0
(-880 -25);
DISPLAY 0.489362 (-880 -25);
PAINT SKYBLUE (-880 -25);
FORCEPROP 0 LAST $SEC 1
J 0
(-875 25);
DISPLAY 0.680851 (-875 25);
PAINT MONO (-875 25);
DISPLAY INVISIBLE (-875 25);
FORCEPROP 0 LAST CDS_SEC 1
J 0
(-875 25);
DISPLAY 1.021277 (-875 25);
DISPLAY INVISIBLE (-875 25);
FORCEPROP 1 LASTPIN (-925 -50) $PN 1
J 0
(-920 -88);
DISPLAY 0.489362 (-920 -88);
PAINT MONO (-920 -88);
FORCEPROP 1 LASTPIN (-925 -250) $PN 2
J 0
(-920 -240);
DISPLAY 0.489362 (-920 -240);
PAINT MONO (-920 -240);
FORCEPROP 1 LAST WATTAGE 1/16W
J 0
(-885 -175);
DISPLAY 0.489362 (-885 -175);
PAINT SKYBLUE (-885 -175);
FORCEPROP 1 LAST PACK_TYPE 0402LF
J 0
(-875 -275);
DISPLAY 0.489362 (-875 -275);
PAINT SKYBLUE (-875 -275);
FORCEPROP 1 LAST MATERIAL EMPTY
J 0
(-885 -225);
DISPLAY 0.489362 (-885 -225);
PAINT RED (-885 -225);
FORCEPROP 1 LAST VALUE 4.7K
J 0
(-880 -75);
DISPLAY 0.489362 (-880 -75);
PAINT SKYBLUE (-880 -75);
FORCEPROP 1 LAST TOLERANCE 5%
J 0
(-880 -125);
DISPLAY 0.489362 (-880 -125);
PAINT SKYBLUE (-880 -125);
FORCEPROP 2 LAST CDS_LIB pure_quanta
J 0
(-925 -150);
DISPLAY INVISIBLE (-925 -150);
FORCEPROP 1 LAST PATH I44
J 0
(-875 25);
DISPLAY 0.978723 (-875 25);
PAINT WHITE (-875 25);
DISPLAY INVISIBLE (-875 25);
FORCEPROP 1 LAST PART_NUMBER CS24702JB10
J 0
(-885 -275);
DISPLAY 0.489362 (-885 -275);
PAINT SKYBLUE (-885 -275);
DISPLAY INVISIBLE (-885 -275);
FORCEADD VCC_CORE..1
(-925 100);
FORCEPROP 3 LASTPIN (-925 50) SIG_NAME PVDD18_S5_P0\g
J 0
(-915 60);
DISPLAY 0.659574 (-915 60);
PAINT MONO (-915 60);
DISPLAY INVISIBLE (-915 60);
FORCEPROP 1 LAST HDL_POWER PVDD18_S5_P0
J 1
(-925 150);
DISPLAY 0.489362 (-925 150);
PAINT GREEN (-925 150);
FORCEPROP 2 LAST CDS_LIB pure_quanta_power
J 0
(-925 100);
DISPLAY INVISIBLE (-925 100);
FORCEPROP 1 LAST PATH I45
J 0
(-875 125);
DISPLAY 0.872340 (-875 125);
PAINT AQUA (-875 125);
DISPLAY INVISIBLE (-875 125);
FORCEADD Q_RES..2
(-650 -150);
FORCEPROP 1 LAST LOCATION R406
J 0
(-605 -25);
DISPLAY 0.489362 (-605 -25);
PAINT SKYBLUE (-605 -25);
FORCEPROP 0 LAST $SEC 1
J 0
(-600 25);
DISPLAY 0.680851 (-600 25);
PAINT MONO (-600 25);
DISPLAY INVISIBLE (-600 25);
FORCEPROP 0 LAST CDS_SEC 1
J 0
(-600 25);
DISPLAY 1.021277 (-600 25);
DISPLAY INVISIBLE (-600 25);
FORCEPROP 1 LASTPIN (-650 -50) $PN 1
J 0
(-645 -88);
DISPLAY 0.489362 (-645 -88);
PAINT MONO (-645 -88);
FORCEPROP 1 LASTPIN (-650 -250) $PN 2
J 0
(-645 -240);
DISPLAY 0.489362 (-645 -240);
PAINT MONO (-645 -240);
FORCEPROP 1 LAST WATTAGE 1/16W
J 0
(-610 -175);
DISPLAY 0.489362 (-610 -175);
PAINT SKYBLUE (-610 -175);
FORCEPROP 1 LAST MATERIAL EMPTY
J 0
(-610 -225);
DISPLAY 0.489362 (-610 -225);
PAINT RED (-610 -225);
FORCEPROP 1 LAST VALUE 4.7K
J 0
(-605 -75);
DISPLAY 0.489362 (-605 -75);
PAINT SKYBLUE (-605 -75);
FORCEPROP 1 LAST TOLERANCE 5%
J 0
(-605 -125);
DISPLAY 0.489362 (-605 -125);
PAINT SKYBLUE (-605 -125);
FORCEPROP 1 LAST PACK_TYPE 0402LF
J 0
(-600 -275);
DISPLAY 0.489362 (-600 -275);
PAINT SKYBLUE (-600 -275);
FORCEPROP 2 LAST CDS_LIB pure_quanta
J 0
(-650 -150);
DISPLAY INVISIBLE (-650 -150);
FORCEPROP 1 LAST PATH I46
J 0
(-600 25);
DISPLAY 0.978723 (-600 25);
PAINT WHITE (-600 25);
DISPLAY INVISIBLE (-600 25);
FORCEPROP 1 LAST PART_NUMBER CS24702JB10
J 0
(-610 -275);
DISPLAY 0.489362 (-610 -275);
PAINT SKYBLUE (-610 -275);
DISPLAY INVISIBLE (-610 -275);
FORCEADD PCA9617ADP..1
(-5975 2300);
FORCEPROP 1 LAST LOCATION U5
J 0
(-6249 2710);
DISPLAY 0.574468 (-6249 2710);
PAINT SKYBLUE (-6249 2710);
FORCEPROP 0 LAST $SEC 1
J 0
(-6225 2850);
DISPLAY 0.680851 (-6225 2850);
PAINT MONO (-6225 2850);
DISPLAY INVISIBLE (-6225 2850);
FORCEPROP 0 LAST CDS_SEC 1
J 0
(-6225 2850);
DISPLAY 0.680851 (-6225 2850);
DISPLAY INVISIBLE (-6225 2850);
FORCEPROP 0 LASTPIN (-5550 2100) $PN 5
J 0
(-5540 2110);
DISPLAY 0.680851 (-5540 2110);
PAINT MONO (-5540 2110);
FORCEPROP 0 LASTPIN (-6400 2100) $PN 4
J 2
(-6410 2110);
DISPLAY 0.680851 (-6410 2110);
PAINT MONO (-6410 2110);
FORCEPROP 0 LASTPIN (-6400 2350) $PN 2
J 2
(-6410 2360);
DISPLAY 0.680851 (-6410 2360);
PAINT MONO (-6410 2360);
FORCEPROP 0 LASTPIN (-5550 2350) $PN 7
J 0
(-5540 2360);
DISPLAY 0.680851 (-5540 2360);
PAINT MONO (-5540 2360);
FORCEPROP 0 LASTPIN (-6400 2250) $PN 3
J 2
(-6410 2260);
DISPLAY 0.680851 (-6410 2260);
PAINT MONO (-6410 2260);
FORCEPROP 0 LASTPIN (-5550 2250) $PN 6
J 0
(-5540 2260);
DISPLAY 0.680851 (-5540 2260);
PAINT MONO (-5540 2260);
FORCEPROP 0 LASTPIN (-6400 2500) $PN 1
J 2
(-6410 2510);
DISPLAY 0.680851 (-6410 2510);
PAINT MONO (-6410 2510);
FORCEPROP 0 LASTPIN (-5550 2500) $PN 8
J 0
(-5540 2510);
DISPLAY 0.680851 (-5540 2510);
PAINT MONO (-5540 2510);
FORCEPROP 1 LAST MATERIAL EMPTY
J 0
(-6249 2605);
DISPLAY 0.723404 (-6249 2605);
PAINT RED (-6249 2605);
FORCEPROP 2 LAST PART_TYPE SMLF
J 0
(-6225 2800);
DISPLAY 0.851064 (-6225 2800);
FORCEPROP 2 LAST VALUE PCA9617ADP
J 0
(-6225 2750);
DISPLAY 0.553191 (-6225 2750);
PAINT SKYBLUE (-6225 2750);
FORCEPROP 1 LAST CDS_LMAN_SYM_OUTLINE -275,300,275,-300
J 0
(-5975 2300);
DISPLAY 0.468085 (-5975 2300);
PAINT GREEN (-5975 2300);
DISPLAY INVISIBLE (-5975 2300);
FORCEPROP 2 LAST CDS_LIB pure_quanta
J 0
(-5975 2300);
DISPLAY INVISIBLE (-5975 2300);
FORCEPROP 1 LAST NEEDS_NO_SIZE TRUE
J 0
(-5700 2000);
DISPLAY 0.468085 (-5700 2000);
PAINT GREEN (-5700 2000);
DISPLAY INVISIBLE (-5700 2000);
FORCEPROP 1 LAST PATH I48
J 0
(-5975 2300);
DISPLAY 0.723404 (-5975 2300);
PAINT GREEN (-5975 2300);
DISPLAY INVISIBLE (-5975 2300);
FORCEPROP 1 LAST PART_NUMBER AL009617K02
J 0
(-6249 2660);
DISPLAY 0.468085 (-6249 2660);
PAINT SKYBLUE (-6249 2660);
DISPLAY INVISIBLE (-6249 2660);
FORCEADD VCC_CORE..1
(-650 175);
FORCEPROP 3 LASTPIN (-650 125) SIG_NAME PVDD18_S5_P0\g
J 0
(-640 135);
DISPLAY 0.659574 (-640 135);
PAINT MONO (-640 135);
DISPLAY INVISIBLE (-640 135);
FORCEPROP 1 LAST HDL_POWER PVDD18_S5_P0
J 1
(-650 225);
DISPLAY 0.489362 (-650 225);
PAINT GREEN (-650 225);
FORCEPROP 2 LAST CDS_LIB pure_quanta_power
J 0
(-650 175);
DISPLAY INVISIBLE (-650 175);
FORCEPROP 1 LAST PATH I49
J 0
(-600 200);
DISPLAY 0.872340 (-600 200);
PAINT AQUA (-600 200);
DISPLAY INVISIBLE (-600 200);
FORCEADD UNIVERSAL_GND..1
(-6450 -1375);
FORCEPROP 3 LASTPIN (-6450 -1325) SIG_NAME GND\g
J 0
(-6440 -1315);
DISPLAY 0.659574 (-6440 -1315);
PAINT MONO (-6440 -1315);
DISPLAY INVISIBLE (-6440 -1315);
FORCEPROP 2 LAST CDS_LIB pure_quanta_power
J 0
(-6450 -1375);
DISPLAY INVISIBLE (-6450 -1375);
FORCEPROP 1 LAST HDL_POWER GND
J 1
(-6425 -1450);
DISPLAY 0.872340 (-6425 -1450);
PAINT GREEN (-6425 -1450);
DISPLAY INVISIBLE (-6425 -1450);
FORCEPROP 1 LAST PATH I5
J 0
(-6375 -1375);
DISPLAY 0.872340 (-6375 -1375);
PAINT AQUA (-6375 -1375);
DISPLAY INVISIBLE (-6375 -1375);
FORCEADD VCC_CORE..1
(-5200 -925);
FORCEPROP 3 LASTPIN (-5200 -975) SIG_NAME PVDD18_S5_P0\g
J 0
(-5190 -965);
DISPLAY 0.659574 (-5190 -965);
PAINT MONO (-5190 -965);
DISPLAY INVISIBLE (-5190 -965);
FORCEPROP 1 LAST HDL_POWER PVDD18_S5_P0
J 1
(-5200 -875);
DISPLAY 0.489362 (-5200 -875);
PAINT GREEN (-5200 -875);
FORCEPROP 2 LAST CDS_LIB pure_quanta_power
J 0
(-5200 -925);
DISPLAY INVISIBLE (-5200 -925);
FORCEPROP 1 LAST PATH I50
J 0
(-5150 -900);
DISPLAY 0.872340 (-5150 -900);
PAINT AQUA (-5150 -900);
DISPLAY INVISIBLE (-5150 -900);
FORCEADD PCA9617ADP..1
R 2
(-5775 -1625);
FORCEPROP 1 LAST LOCATION U96
J 2
(-5501 -1215);
DISPLAY 0.723404 (-5501 -1215);
PAINT GREEN (-5501 -1215);
FORCEPROP 2 LAST SEC 1
J 0
(-5525 -1075);
DISPLAY 0.680851 (-5525 -1075);
PAINT MONO (-5525 -1075);
DISPLAY INVISIBLE (-5525 -1075);
FORCEPROP 2 LASTPIN (-6200 -1825) $PN 5
J 2
(-6210 -1815);
DISPLAY 0.680851 (-6210 -1815);
PAINT MONO (-6210 -1815);
FORCEPROP 2 LASTPIN (-5350 -1825) $PN 4
J 0
(-5340 -1815);
DISPLAY 0.680851 (-5340 -1815);
PAINT MONO (-5340 -1815);
FORCEPROP 2 LASTPIN (-5350 -1575) $PN 2
J 0
(-5340 -1565);
DISPLAY 0.680851 (-5340 -1565);
PAINT MONO (-5340 -1565);
FORCEPROP 2 LASTPIN (-6200 -1575) $PN 7
J 2
(-6210 -1565);
DISPLAY 0.680851 (-6210 -1565);
PAINT MONO (-6210 -1565);
FORCEPROP 2 LASTPIN (-5350 -1675) $PN 3
J 0
(-5340 -1665);
DISPLAY 0.680851 (-5340 -1665);
PAINT MONO (-5340 -1665);
FORCEPROP 2 LASTPIN (-6200 -1675) $PN 6
J 2
(-6210 -1665);
DISPLAY 0.680851 (-6210 -1665);
PAINT MONO (-6210 -1665);
FORCEPROP 2 LASTPIN (-5350 -1425) $PN 1
J 0
(-5340 -1415);
DISPLAY 0.680851 (-5340 -1415);
PAINT MONO (-5340 -1415);
FORCEPROP 2 LASTPIN (-6200 -1425) $PN 8
J 2
(-6210 -1415);
DISPLAY 0.680851 (-6210 -1415);
PAINT MONO (-6210 -1415);
FORCEPROP 2 LAST VALUE PCA9617ADP
J 2
(-5525 -1175);
DISPLAY 0.680851 (-5525 -1175);
FORCEPROP 2 LAST PART_TYPE SMLF
J 2
(-5525 -1125);
DISPLAY 0.680851 (-5525 -1125);
FORCEPROP 1 LAST MATERIAL IC
J 2
(-5501 -1320);
DISPLAY 0.723404 (-5501 -1320);
PAINT GREEN (-5501 -1320);
FORCEPROP 2 LAST SEC_TYPE 
J 0
(-5525 -1075);
DISPLAY 0.680851 (-5525 -1075);
DISPLAY INVISIBLE (-5525 -1075);
FORCEPROP 1 LAST CDS_LMAN_SYM_OUTLINE -275,300,275,-300
J 2
(-5775 -1625);
DISPLAY 0.468085 (-5775 -1625);
PAINT GREEN (-5775 -1625);
DISPLAY INVISIBLE (-5775 -1625);
FORCEPROP 1 LAST NEEDS_NO_SIZE TRUE
J 2
(-6050 -1925);
DISPLAY 0.468085 (-6050 -1925);
PAINT GREEN (-6050 -1925);
DISPLAY INVISIBLE (-6050 -1925);
FORCEPROP 2 LAST CDS_LIB pure_quanta
J 2
(-5775 -1625);
DISPLAY INVISIBLE (-5775 -1625);
FORCEPROP 1 LAST PATH I51
J 2
(-5775 -1625);
DISPLAY 0.723404 (-5775 -1625);
PAINT GREEN (-5775 -1625);
DISPLAY INVISIBLE (-5775 -1625);
FORCEPROP 1 LAST PART_NUMBER AL009617K02
J 2
(-5501 -1265);
DISPLAY 0.723404 (-5501 -1265);
PAINT GREEN (-5501 -1265);
DISPLAY INVISIBLE (-5501 -1265);
FORCEADD UNIVERSAL_POWER..1
R 2
(-6825 -1975);
FORCEPROP 3 LASTPIN (-6825 -2025) SIG_NAME P3V3_AUX\g
J 0
(-6815 -2015);
DISPLAY 0.659574 (-6815 -2015);
PAINT MONO (-6815 -2015);
DISPLAY INVISIBLE (-6815 -2015);
FORCEPROP 1 LAST HDL_POWER P3V3_AUX
J 1
(-6825 -1925);
DISPLAY 0.489362 (-6825 -1925);
PAINT GREEN (-6825 -1925);
FORCEPROP 2 LAST CDS_LIB pure_quanta_power
J 0
(-6825 -1975);
DISPLAY INVISIBLE (-6825 -1975);
FORCEPROP 1 LAST PATH I52
J 2
(-6875 -1950);
DISPLAY 0.872340 (-6875 -1950);
PAINT AQUA (-6875 -1950);
DISPLAY INVISIBLE (-6875 -1950);
FORCEADD VCC_CORE..1
(-5350 1375);
FORCEPROP 3 LASTPIN (-5350 1325) SIG_NAME PVDD11_S3_P0\g
J 0
(-5340 1335);
DISPLAY 0.659574 (-5340 1335);
PAINT MONO (-5340 1335);
DISPLAY INVISIBLE (-5340 1335);
FORCEPROP 1 LAST HDL_POWER PVDD11_S3_P0
J 1
(-5350 1425);
DISPLAY 0.489362 (-5350 1425);
PAINT GREEN (-5350 1425);
FORCEPROP 2 LAST CDS_LIB pure_quanta_power
J 0
(-5350 1375);
DISPLAY INVISIBLE (-5350 1375);
FORCEPROP 1 LAST PATH I54
J 0
(-5300 1400);
DISPLAY 0.872340 (-5300 1400);
PAINT AQUA (-5300 1400);
DISPLAY INVISIBLE (-5300 1400);
FORCEADD UNIVERSAL_GND..1
(-5275 950);
FORCEPROP 3 LASTPIN (-5275 1000) SIG_NAME GND\g
J 0
(-5265 1010);
DISPLAY 0.659574 (-5265 1010);
PAINT MONO (-5265 1010);
DISPLAY INVISIBLE (-5265 1010);
FORCEPROP 2 LAST CDS_LIB pure_quanta_power
J 0
(-5275 950);
DISPLAY INVISIBLE (-5275 950);
FORCEPROP 1 LAST HDL_POWER GND
J 1
(-5250 875);
DISPLAY 0.872340 (-5250 875);
PAINT GREEN (-5250 875);
DISPLAY INVISIBLE (-5250 875);
FORCEPROP 1 LAST PATH I55
J 0
(-5200 950);
DISPLAY 0.872340 (-5200 950);
PAINT AQUA (-5200 950);
DISPLAY INVISIBLE (-5200 950);
FORCEADD Q_CAP..1
(-5275 1150);
FORCEPROP 1 LAST LOCATION C3
J 0
(-5225 1275);
DISPLAY 0.617021 (-5225 1275);
PAINT SKYBLUE (-5225 1275);
FORCEPROP 0 LAST $SEC 1
J 0
(-5225 1300);
DISPLAY 0.680851 (-5225 1300);
PAINT MONO (-5225 1300);
DISPLAY INVISIBLE (-5225 1300);
FORCEPROP 0 LAST CDS_SEC 1
J 0
(-5225 1300);
DISPLAY 0.680851 (-5225 1300);
DISPLAY INVISIBLE (-5225 1300);
FORCEPROP 1 LASTPIN (-5275 1250) $PN 1
J 0
(-5265 1230);
DISPLAY 0.787234 (-5265 1230);
PAINT MONO (-5265 1230);
FORCEPROP 1 LASTPIN (-5275 1050) $PN 2
J 0
(-5265 1030);
DISPLAY 0.787234 (-5265 1030);
PAINT MONO (-5265 1030);
FORCEPROP 1 LAST PACK_TYPE 0402
J 0
(-5225 1050);
DISPLAY 0.489362 (-5225 1050);
PAINT SKYBLUE (-5225 1050);
FORCEPROP 1 LAST MATERIAL X7R
J 0
(-5225 1100);
DISPLAY 0.489362 (-5225 1100);
PAINT SKYBLUE (-5225 1100);
FORCEPROP 1 LAST VALUE 0.1UF
J 0
(-5225 1250);
DISPLAY 0.489362 (-5225 1250);
PAINT SKYBLUE (-5225 1250);
FORCEPROP 1 LAST TOLERANCE 10%
J 0
(-5225 1150);
DISPLAY 0.489362 (-5225 1150);
PAINT SKYBLUE (-5225 1150);
FORCEPROP 1 LAST VOLTAGE 25V
J 0
(-5225 1200);
DISPLAY 0.489362 (-5225 1200);
PAINT SKYBLUE (-5225 1200);
FORCEPROP 2 LAST CDS_LIB pure_quanta
J 0
(-5275 1150);
DISPLAY INVISIBLE (-5275 1150);
FORCEPROP 1 LAST PATH I56
J 0
(-5225 1300);
DISPLAY 0.978723 (-5225 1300);
PAINT WHITE (-5225 1300);
DISPLAY INVISIBLE (-5225 1300);
FORCEPROP 1 LAST PART_NUMBER CH4104K1B00
J 0
(-5225 1000);
DISPLAY 0.489362 (-5225 1000);
PAINT SKYBLUE (-5225 1000);
DISPLAY INVISIBLE (-5225 1000);
FORCEADD UNIVERSAL_POWER..1
R 2
(-6500 1475);
FORCEPROP 3 LASTPIN (-6500 1425) SIG_NAME P3V3_AUX\g
J 0
(-6490 1435);
DISPLAY 0.659574 (-6490 1435);
PAINT MONO (-6490 1435);
DISPLAY INVISIBLE (-6490 1435);
FORCEPROP 1 LAST HDL_POWER P3V3_AUX
J 1
(-6500 1525);
DISPLAY 0.489362 (-6500 1525);
PAINT GREEN (-6500 1525);
FORCEPROP 2 LAST CDS_LIB pure_quanta_power
J 0
(-6500 1475);
DISPLAY INVISIBLE (-6500 1475);
FORCEPROP 1 LAST PATH I57
J 2
(-6550 1500);
DISPLAY 0.872340 (-6550 1500);
PAINT AQUA (-6550 1500);
DISPLAY INVISIBLE (-6550 1500);
FORCEADD UNIVERSAL_GND..1
(-6675 1000);
FORCEPROP 3 LASTPIN (-6675 1050) SIG_NAME GND\g
J 0
(-6665 1060);
DISPLAY 0.659574 (-6665 1060);
PAINT MONO (-6665 1060);
DISPLAY INVISIBLE (-6665 1060);
FORCEPROP 2 LAST CDS_LIB pure_quanta_power
J 0
(-6675 1000);
DISPLAY INVISIBLE (-6675 1000);
FORCEPROP 1 LAST HDL_POWER GND
J 1
(-6650 925);
DISPLAY 0.872340 (-6650 925);
PAINT GREEN (-6650 925);
DISPLAY INVISIBLE (-6650 925);
FORCEPROP 1 LAST PATH I58
J 0
(-6600 1000);
DISPLAY 0.872340 (-6600 1000);
PAINT AQUA (-6600 1000);
DISPLAY INVISIBLE (-6600 1000);
FORCEADD Q_CAP..1
(-6675 1200);
FORCEPROP 1 LAST LOCATION C2
J 2
(-6725 1350);
DISPLAY 0.489362 (-6725 1350);
PAINT SKYBLUE (-6725 1350);
FORCEPROP 0 LAST $SEC 1
J 0
(-6725 1375);
DISPLAY 0.680851 (-6725 1375);
PAINT MONO (-6725 1375);
DISPLAY INVISIBLE (-6725 1375);
FORCEPROP 0 LAST CDS_SEC 1
J 0
(-6725 1375);
DISPLAY 0.680851 (-6725 1375);
DISPLAY INVISIBLE (-6725 1375);
FORCEPROP 1 LASTPIN (-6675 1300) $PN 1
J 0
(-6665 1280);
DISPLAY 0.787234 (-6665 1280);
PAINT MONO (-6665 1280);
FORCEPROP 1 LASTPIN (-6675 1100) $PN 2
J 0
(-6665 1080);
DISPLAY 0.787234 (-6665 1080);
PAINT MONO (-6665 1080);
FORCEPROP 1 LAST MATERIAL X7R
J 2
(-6725 1150);
DISPLAY 0.489362 (-6725 1150);
PAINT SKYBLUE (-6725 1150);
FORCEPROP 1 LAST TOLERANCE 10%
J 2
(-6725 1200);
DISPLAY 0.489362 (-6725 1200);
PAINT SKYBLUE (-6725 1200);
FORCEPROP 1 LAST VALUE 0.1UF
J 2
(-6725 1300);
DISPLAY 0.489362 (-6725 1300);
PAINT SKYBLUE (-6725 1300);
FORCEPROP 1 LAST VOLTAGE 25V
J 2
(-6725 1250);
DISPLAY 0.489362 (-6725 1250);
PAINT SKYBLUE (-6725 1250);
FORCEPROP 1 LAST PACK_TYPE 0402
J 2
(-6725 1100);
DISPLAY 0.489362 (-6725 1100);
PAINT SKYBLUE (-6725 1100);
FORCEPROP 2 LAST CDS_LIB pure_quanta
J 0
(-6675 1200);
DISPLAY INVISIBLE (-6675 1200);
FORCEPROP 1 LAST PATH I59
J 0
(-6625 1350);
DISPLAY 0.978723 (-6625 1350);
PAINT WHITE (-6625 1350);
DISPLAY INVISIBLE (-6625 1350);
FORCEPROP 1 LAST PART_NUMBER CH4104K1B00
J 0
(-6625 1050);
DISPLAY 0.489362 (-6625 1050);
PAINT SKYBLUE (-6625 1050);
DISPLAY INVISIBLE (-6625 1050);
FORCEADD Q_CAP..1
(-6450 -1175);
FORCEPROP 1 LAST LOCATION C611
J 0
(-6400 -1075);
DISPLAY 0.489362 (-6400 -1075);
PAINT SKYBLUE (-6400 -1075);
FORCEPROP 2 LAST $SEC 1
J 0
(-6400 -975);
DISPLAY 0.680851 (-6400 -975);
PAINT MONO (-6400 -975);
DISPLAY INVISIBLE (-6400 -975);
FORCEPROP 2 LAST CDS_SEC 1
J 0
(-6400 -975);
DISPLAY 0.680851 (-6400 -975);
DISPLAY INVISIBLE (-6400 -975);
FORCEPROP 1 LASTPIN (-6450 -1075) $PN 1
J 0
(-6440 -1095);
DISPLAY 0.489362 (-6440 -1095);
PAINT MONO (-6440 -1095);
FORCEPROP 1 LASTPIN (-6450 -1275) $PN 2
J 0
(-6440 -1295);
DISPLAY 0.489362 (-6440 -1295);
PAINT MONO (-6440 -1295);
FORCEPROP 1 LAST VOLTAGE 25V
J 2
(-6500 -1125);
DISPLAY 0.489362 (-6500 -1125);
PAINT SKYBLUE (-6500 -1125);
FORCEPROP 1 LAST VALUE 0.1UF
J 2
(-6500 -1075);
DISPLAY 0.489362 (-6500 -1075);
PAINT SKYBLUE (-6500 -1075);
FORCEPROP 1 LAST TOLERANCE 10%
J 2
(-6500 -1175);
DISPLAY 0.489362 (-6500 -1175);
PAINT SKYBLUE (-6500 -1175);
FORCEPROP 1 LAST PACK_TYPE 0402
J 2
(-6500 -1275);
DISPLAY 0.489362 (-6500 -1275);
PAINT SKYBLUE (-6500 -1275);
FORCEPROP 1 LAST MATERIAL X7R
J 2
(-6500 -1225);
DISPLAY 0.489362 (-6500 -1225);
PAINT SKYBLUE (-6500 -1225);
FORCEPROP 2 LAST CDS_LIB pure_quanta
J 0
(-6450 -1175);
DISPLAY INVISIBLE (-6450 -1175);
FORCEPROP 1 LAST PATH I6
J 0
(-6400 -1025);
DISPLAY 0.978723 (-6400 -1025);
PAINT WHITE (-6400 -1025);
DISPLAY INVISIBLE (-6400 -1025);
FORCEPROP 1 LAST PART_NUMBER CH4104K1B00
J 0
(-6400 -1325);
DISPLAY 0.489362 (-6400 -1325);
PAINT SKYBLUE (-6400 -1325);
DISPLAY INVISIBLE (-6400 -1325);
FORCEADD UNIVERSAL_GND..1
(-5400 375);
FORCEPROP 3 LASTPIN (-5400 425) SIG_NAME GND\g
J 0
(-5390 435);
DISPLAY 0.659574 (-5390 435);
PAINT MONO (-5390 435);
DISPLAY INVISIBLE (-5390 435);
FORCEPROP 2 LAST CDS_LIB pure_quanta_power
J 0
(-5400 375);
DISPLAY INVISIBLE (-5400 375);
FORCEPROP 1 LAST HDL_POWER GND
J 1
(-5375 300);
DISPLAY 0.872340 (-5375 300);
PAINT GREEN (-5375 300);
DISPLAY INVISIBLE (-5375 300);
FORCEPROP 1 LAST PATH I60
J 0
(-5325 375);
DISPLAY 0.872340 (-5325 375);
PAINT AQUA (-5325 375);
DISPLAY INVISIBLE (-5325 375);
FORCEADD UNIVERSAL_POWER..1
R 2
(-7050 400);
FORCEPROP 3 LASTPIN (-7050 350) SIG_NAME P3V3_AUX\g
J 0
(-7040 360);
DISPLAY 0.659574 (-7040 360);
PAINT MONO (-7040 360);
DISPLAY INVISIBLE (-7040 360);
FORCEPROP 1 LAST HDL_POWER P3V3_AUX
J 1
(-7050 450);
DISPLAY 0.489362 (-7050 450);
PAINT GREEN (-7050 450);
FORCEPROP 2 LAST CDS_LIB pure_quanta_power
J 0
(-7050 400);
DISPLAY INVISIBLE (-7050 400);
FORCEPROP 1 LAST PATH I61
J 2
(-7100 425);
DISPLAY 0.872340 (-7100 425);
PAINT AQUA (-7100 425);
DISPLAY INVISIBLE (-7100 425);
FORCEADD Q_RES..2
(-7050 125);
FORCEPROP 1 LAST LOCATION R201
J 0
(-7005 250);
DISPLAY 0.638298 (-7005 250);
PAINT SKYBLUE (-7005 250);
FORCEPROP 0 LAST $SEC 1
J 0
(-7000 300);
DISPLAY 0.680851 (-7000 300);
PAINT MONO (-7000 300);
DISPLAY INVISIBLE (-7000 300);
FORCEPROP 0 LAST CDS_SEC 1
J 0
(-7000 300);
DISPLAY 0.680851 (-7000 300);
DISPLAY INVISIBLE (-7000 300);
FORCEPROP 1 LASTPIN (-7050 225) $PN 1
J 0
(-7045 187);
DISPLAY 0.787234 (-7045 187);
PAINT MONO (-7045 187);
FORCEPROP 1 LASTPIN (-7050 25) $PN 2
J 0
(-7045 35);
DISPLAY 0.787234 (-7045 35);
PAINT MONO (-7045 35);
FORCEPROP 1 LAST VALUE 4.7K
J 0
(-7005 200);
DISPLAY 0.489362 (-7005 200);
PAINT SKYBLUE (-7005 200);
FORCEPROP 1 LAST PACK_TYPE 0402LF
J 0
(-7000 0);
DISPLAY 0.489362 (-7000 0);
PAINT SKYBLUE (-7000 0);
FORCEPROP 1 LAST MATERIAL EMPTY
J 0
(-7010 50);
DISPLAY 0.489362 (-7010 50);
PAINT RED (-7010 50);
FORCEPROP 1 LAST WATTAGE 1/16W
J 0
(-7010 100);
DISPLAY 0.489362 (-7010 100);
PAINT SKYBLUE (-7010 100);
FORCEPROP 1 LAST TOLERANCE 5%
J 0
(-7005 150);
DISPLAY 0.489362 (-7005 150);
PAINT SKYBLUE (-7005 150);
FORCEPROP 2 LAST CDS_LIB pure_quanta
J 0
(-7050 125);
DISPLAY INVISIBLE (-7050 125);
FORCEPROP 1 LAST PATH I62
J 0
(-7000 300);
DISPLAY 0.978723 (-7000 300);
PAINT WHITE (-7000 300);
DISPLAY INVISIBLE (-7000 300);
FORCEPROP 1 LAST PART_NUMBER CS24702JB10
J 0
(-7010 0);
DISPLAY 0.489362 (-7010 0);
PAINT SKYBLUE (-7010 0);
DISPLAY INVISIBLE (-7010 0);
FORCEADD OFFPAGE..2
(-1350 2350);
FORCEPROP 2 LAST $XR1 161 
J 0
(-1041 2350);
DISPLAY 0.638298 (-1041 2350);
PAINT MONO (-1041 2350);
FORCEPROP 2 LAST $XR0 160 
J 0
(-1161 2350);
DISPLAY 0.638298 (-1161 2350);
PAINT MONO (-1161 2350);
FORCEPROP 2 LAST CDS_LIB standard
J 0
(-1350 2350);
DISPLAY INVISIBLE (-1350 2350);
FORCEPROP 1 LAST OFFPAGE TRUE
J 0
(-1025 2225);
DISPLAY 0.872340 (-1025 2225);
PAINT GREEN (-1025 2225);
DISPLAY INVISIBLE (-1025 2225);
FORCEPROP 1 LAST COMMENT_BODY TRUE
J 0
(-1395 2255);
DISPLAY 0.872340 (-1395 2255);
PAINT GREEN (-1395 2255);
DISPLAY INVISIBLE (-1395 2255);
FORCEPROP 2 LAST PATH I63
J 0
(-1025 2400);
DISPLAY 0.680851 (-1025 2400);
DISPLAY INVISIBLE (-1025 2400);
FORCEADD OFFPAGE..3
(-1375 2250);
FORCEPROP 2 LAST $XR1 161 
J 0
(-1041 2250);
DISPLAY 0.638298 (-1041 2250);
PAINT MONO (-1041 2250);
FORCEPROP 2 LAST $XR0 160 
J 0
(-1161 2250);
DISPLAY 0.638298 (-1161 2250);
PAINT MONO (-1161 2250);
FORCEPROP 2 LAST CDS_LIB standard
J 0
(-1375 2250);
DISPLAY INVISIBLE (-1375 2250);
FORCEPROP 1 LAST OFFPAGE TRUE
J 0
(-1050 2125);
DISPLAY 0.872340 (-1050 2125);
PAINT GREEN (-1050 2125);
DISPLAY INVISIBLE (-1050 2125);
FORCEPROP 1 LAST COMMENT_BODY TRUE
J 0
(-1425 2150);
DISPLAY 0.872340 (-1425 2150);
PAINT PEACH (-1425 2150);
DISPLAY INVISIBLE (-1425 2150);
FORCEPROP 2 LAST PATH I64
J 0
(-1025 2300);
DISPLAY 0.680851 (-1025 2300);
DISPLAY INVISIBLE (-1025 2300);
FORCEADD Q_RES..1
(-4400 800);
FORCEPROP 1 LAST LOCATION R202
J 0
(-4675 825);
DISPLAY 0.978723 (-4675 825);
FORCEPROP 0 LAST $SEC 1
J 0
(-4575 875);
DISPLAY 0.680851 (-4575 875);
PAINT MONO (-4575 875);
DISPLAY INVISIBLE (-4575 875);
FORCEPROP 0 LAST CDS_SEC 1
J 0
(-4575 875);
DISPLAY 0.680851 (-4575 875);
DISPLAY INVISIBLE (-4575 875);
FORCEPROP 1 LASTPIN (-4500 800) $PN 1
J 0
(-4488 812);
DISPLAY 0.787234 (-4488 812);
PAINT MONO (-4488 812);
FORCEPROP 1 LASTPIN (-4300 800) $PN 2
J 0
(-4338 812);
DISPLAY 0.787234 (-4338 812);
PAINT MONO (-4338 812);
FORCEPROP 1 LAST MATERIAL CHIP
J 0
(-4150 800);
DISPLAY 0.638298 (-4150 800);
FORCEPROP 1 LAST VALUE 0
J 2
(-4200 800);
DISPLAY 0.638298 (-4200 800);
FORCEPROP 1 LAST PACK_TYPE 0402LF
J 0
(-3975 800);
DISPLAY 0.638298 (-3975 800);
FORCEPROP 1 LAST WATTAGE 1/16W
J 2
(-4425 650);
DISPLAY 0.978723 (-4425 650);
DISPLAY INVISIBLE (-4425 650);
FORCEPROP 1 LAST TOLERANCE 5%
J 0
(-4425 700);
DISPLAY 0.978723 (-4425 700);
DISPLAY INVISIBLE (-4425 700);
FORCEPROP 2 LAST CDS_LIB pure_quanta
J 0
(-4400 800);
DISPLAY INVISIBLE (-4400 800);
FORCEPROP 1 LAST PATH I67
J 0
(-4450 950);
DISPLAY 0.978723 (-4450 950);
PAINT WHITE (-4450 950);
DISPLAY INVISIBLE (-4450 950);
FORCEPROP 1 LAST PART_NUMBER CS00002JB13
J 0
(-4275 825);
DISPLAY 0.978723 (-4275 825);
DISPLAY INVISIBLE (-4275 825);
FORCEADD Q_RES..1
(-4375 700);
FORCEPROP 1 LAST LOCATION R206
J 0
(-4650 725);
DISPLAY 0.978723 (-4650 725);
FORCEPROP 0 LAST $SEC 1
J 0
(-4575 775);
DISPLAY 0.680851 (-4575 775);
PAINT MONO (-4575 775);
DISPLAY INVISIBLE (-4575 775);
FORCEPROP 0 LAST CDS_SEC 1
J 0
(-4575 775);
DISPLAY 0.680851 (-4575 775);
DISPLAY INVISIBLE (-4575 775);
FORCEPROP 1 LASTPIN (-4475 700) $PN 1
J 0
(-4463 712);
DISPLAY 0.787234 (-4463 712);
PAINT MONO (-4463 712);
FORCEPROP 1 LASTPIN (-4275 700) $PN 2
J 0
(-4313 712);
DISPLAY 0.787234 (-4313 712);
PAINT MONO (-4313 712);
FORCEPROP 1 LAST MATERIAL CHIP
J 0
(-4125 700);
DISPLAY 0.638298 (-4125 700);
FORCEPROP 1 LAST PACK_TYPE 0402LF
J 0
(-3950 700);
DISPLAY 0.638298 (-3950 700);
FORCEPROP 1 LAST VALUE 0
J 2
(-4175 700);
DISPLAY 0.638298 (-4175 700);
FORCEPROP 2 LAST CDS_LIB pure_quanta
J 0
(-4375 700);
DISPLAY INVISIBLE (-4375 700);
FORCEPROP 1 LAST WATTAGE 1/16W
J 2
(-4400 550);
DISPLAY 0.978723 (-4400 550);
DISPLAY INVISIBLE (-4400 550);
FORCEPROP 1 LAST TOLERANCE 5%
J 0
(-4400 600);
DISPLAY 0.978723 (-4400 600);
DISPLAY INVISIBLE (-4400 600);
FORCEPROP 1 LAST PATH I68
J 0
(-4425 850);
DISPLAY 0.978723 (-4425 850);
PAINT WHITE (-4425 850);
DISPLAY INVISIBLE (-4425 850);
FORCEPROP 1 LAST PART_NUMBER CS00002JB13
J 0
(-4250 725);
DISPLAY 0.978723 (-4250 725);
DISPLAY INVISIBLE (-4250 725);
FORCEADD OFFPAGE..2
(-700 800);
FORCEPROP 2 LAST $XR1 161 
J 0
(-391 800);
DISPLAY 0.638298 (-391 800);
PAINT MONO (-391 800);
FORCEPROP 2 LAST $XR0 160 
J 0
(-511 800);
DISPLAY 0.638298 (-511 800);
PAINT MONO (-511 800);
FORCEPROP 2 LAST CDS_LIB standard
J 0
(-700 800);
DISPLAY INVISIBLE (-700 800);
FORCEPROP 1 LAST OFFPAGE TRUE
J 0
(-375 675);
DISPLAY 0.872340 (-375 675);
PAINT GREEN (-375 675);
DISPLAY INVISIBLE (-375 675);
FORCEPROP 1 LAST COMMENT_BODY TRUE
J 0
(-745 705);
DISPLAY 0.872340 (-745 705);
PAINT GREEN (-745 705);
DISPLAY INVISIBLE (-745 705);
FORCEPROP 2 LAST PATH I69
J 0
(-525 875);
DISPLAY 0.680851 (-525 875);
DISPLAY INVISIBLE (-525 875);
FORCEADD UNIVERSAL_POWER..1
R 2
(-6275 -900);
FORCEPROP 3 LASTPIN (-6275 -950) SIG_NAME P3V3_AUX\g
J 0
(-6265 -940);
DISPLAY 0.659574 (-6265 -940);
PAINT MONO (-6265 -940);
DISPLAY INVISIBLE (-6265 -940);
FORCEPROP 1 LAST HDL_POWER P3V3_AUX
J 1
(-6275 -850);
DISPLAY 0.489362 (-6275 -850);
PAINT GREEN (-6275 -850);
FORCEPROP 2 LAST CDS_LIB pure_quanta_power
J 0
(-6275 -900);
DISPLAY INVISIBLE (-6275 -900);
FORCEPROP 1 LAST PATH I7
J 2
(-6325 -875);
DISPLAY 0.872340 (-6325 -875);
PAINT AQUA (-6325 -875);
DISPLAY INVISIBLE (-6325 -875);
FORCEADD OFFPAGE..3
(-725 700);
FORCEPROP 2 LAST $XR1 161 
J 0
(-391 700);
DISPLAY 0.638298 (-391 700);
PAINT MONO (-391 700);
FORCEPROP 2 LAST $XR0 160 
J 0
(-511 700);
DISPLAY 0.638298 (-511 700);
PAINT MONO (-511 700);
FORCEPROP 2 LAST CDS_LIB standard
J 0
(-725 700);
DISPLAY INVISIBLE (-725 700);
FORCEPROP 1 LAST OFFPAGE TRUE
J 0
(-400 575);
DISPLAY 0.872340 (-400 575);
PAINT GREEN (-400 575);
DISPLAY INVISIBLE (-400 575);
FORCEPROP 1 LAST COMMENT_BODY TRUE
J 0
(-775 600);
DISPLAY 0.872340 (-775 600);
PAINT PEACH (-775 600);
DISPLAY INVISIBLE (-775 600);
FORCEPROP 2 LAST PATH I70
J 0
(-525 775);
DISPLAY 0.680851 (-525 775);
DISPLAY INVISIBLE (-525 775);
FORCEADD Q_RES..1
(-2350 800);
FORCEPROP 1 LAST LOCATION R274
J 0
(-2625 800);
DISPLAY 0.978723 (-2625 800);
FORCEPROP 0 LAST $SEC 1
J 0
(-1925 850);
DISPLAY 0.680851 (-1925 850);
PAINT MONO (-1925 850);
DISPLAY INVISIBLE (-1925 850);
FORCEPROP 0 LAST CDS_SEC 1
J 0
(-1925 850);
DISPLAY 0.680851 (-1925 850);
DISPLAY INVISIBLE (-1925 850);
FORCEPROP 1 LASTPIN (-2450 800) $PN 1
J 0
(-2438 812);
DISPLAY 0.787234 (-2438 812);
PAINT MONO (-2438 812);
FORCEPROP 1 LASTPIN (-2250 800) $PN 2
J 0
(-2288 812);
DISPLAY 0.787234 (-2288 812);
PAINT MONO (-2288 812);
FORCEPROP 1 LAST PACK_TYPE 0402LF
J 0
(-1925 800);
DISPLAY 0.638298 (-1925 800);
FORCEPROP 1 LAST MATERIAL CHIP
J 0
(-2100 800);
DISPLAY 0.638298 (-2100 800);
FORCEPROP 1 LAST VALUE 0
J 2
(-2150 800);
DISPLAY 0.638298 (-2150 800);
FORCEPROP 1 LAST WATTAGE 1/16W
J 2
(-2375 650);
DISPLAY 0.978723 (-2375 650);
DISPLAY INVISIBLE (-2375 650);
FORCEPROP 1 LAST TOLERANCE 5%
J 0
(-2375 700);
DISPLAY 0.978723 (-2375 700);
DISPLAY INVISIBLE (-2375 700);
FORCEPROP 2 LAST CDS_LIB pure_quanta
J 0
(-2350 800);
DISPLAY INVISIBLE (-2350 800);
FORCEPROP 1 LAST PATH I71
J 0
(-2400 950);
DISPLAY 0.978723 (-2400 950);
PAINT WHITE (-2400 950);
DISPLAY INVISIBLE (-2400 950);
FORCEPROP 1 LAST PART_NUMBER CS00002JB13
J 0
(-2225 825);
DISPLAY 0.978723 (-2225 825);
DISPLAY INVISIBLE (-2225 825);
FORCEADD Q_RES..1
(-2325 700);
FORCEPROP 1 LAST LOCATION R281
J 0
(-2600 700);
DISPLAY 0.978723 (-2600 700);
FORCEPROP 0 LAST $SEC 1
J 0
(-1900 750);
DISPLAY 0.680851 (-1900 750);
PAINT MONO (-1900 750);
DISPLAY INVISIBLE (-1900 750);
FORCEPROP 0 LAST CDS_SEC 1
J 0
(-1900 750);
DISPLAY 0.680851 (-1900 750);
DISPLAY INVISIBLE (-1900 750);
FORCEPROP 1 LASTPIN (-2425 700) $PN 1
J 0
(-2413 712);
DISPLAY 0.787234 (-2413 712);
PAINT MONO (-2413 712);
FORCEPROP 1 LASTPIN (-2225 700) $PN 2
J 0
(-2263 712);
DISPLAY 0.787234 (-2263 712);
PAINT MONO (-2263 712);
FORCEPROP 1 LAST PACK_TYPE 0402LF
J 0
(-1900 700);
DISPLAY 0.638298 (-1900 700);
FORCEPROP 1 LAST VALUE 0
J 2
(-2125 700);
DISPLAY 0.638298 (-2125 700);
FORCEPROP 1 LAST MATERIAL CHIP
J 0
(-2075 700);
DISPLAY 0.638298 (-2075 700);
FORCEPROP 1 LAST WATTAGE 1/16W
J 2
(-2350 550);
DISPLAY 0.978723 (-2350 550);
DISPLAY INVISIBLE (-2350 550);
FORCEPROP 1 LAST TOLERANCE 5%
J 0
(-2350 600);
DISPLAY 0.978723 (-2350 600);
DISPLAY INVISIBLE (-2350 600);
FORCEPROP 2 LAST CDS_LIB pure_quanta
J 0
(-2325 700);
DISPLAY INVISIBLE (-2325 700);
FORCEPROP 1 LAST PATH I72
J 0
(-2375 850);
DISPLAY 0.978723 (-2375 850);
PAINT WHITE (-2375 850);
DISPLAY INVISIBLE (-2375 850);
FORCEPROP 1 LAST PART_NUMBER CS00002JB13
J 0
(-2200 725);
DISPLAY 0.978723 (-2200 725);
DISPLAY INVISIBLE (-2200 725);
FORCEADD Q_RES..2
(-1750 -150);
FORCEPROP 1 LAST LOCATION R322
J 0
(-1705 -25);
DISPLAY 0.510638 (-1705 -25);
FORCEPROP 0 LAST $SEC 1
J 0
(-1700 0);
DISPLAY 0.680851 (-1700 0);
PAINT MONO (-1700 0);
DISPLAY INVISIBLE (-1700 0);
FORCEPROP 0 LAST CDS_SEC 1
J 0
(-1700 0);
DISPLAY 0.680851 (-1700 0);
DISPLAY INVISIBLE (-1700 0);
FORCEPROP 1 LASTPIN (-1750 -50) $PN 1
J 0
(-1745 -88);
DISPLAY 0.787234 (-1745 -88);
PAINT MONO (-1745 -88);
FORCEPROP 1 LASTPIN (-1750 -250) $PN 2
J 0
(-1745 -240);
DISPLAY 0.787234 (-1745 -240);
PAINT MONO (-1745 -240);
FORCEPROP 1 LAST MATERIAL EMPTY
J 0
(-1710 -225);
DISPLAY 0.510638 (-1710 -225);
PAINT RED (-1710 -225);
FORCEPROP 1 LAST WATTAGE 1/16W
J 0
(-1710 -175);
DISPLAY 0.510638 (-1710 -175);
FORCEPROP 1 LAST TOLERANCE 1%
J 0
(-1705 -125);
DISPLAY 0.510638 (-1705 -125);
FORCEPROP 1 LAST VALUE 1K
J 0
(-1705 -75);
DISPLAY 0.510638 (-1705 -75);
FORCEPROP 1 LAST PACK_TYPE 0402LF
J 0
(-1725 -275);
DISPLAY 0.510638 (-1725 -275);
FORCEPROP 2 LAST CDS_LIB pure_quanta
J 0
(-1750 -150);
DISPLAY INVISIBLE (-1750 -150);
FORCEPROP 1 LAST PATH I73
J 0
(-1700 25);
DISPLAY 0.978723 (-1700 25);
PAINT WHITE (-1700 25);
DISPLAY INVISIBLE (-1700 25);
FORCEPROP 1 LAST PART_NUMBER CS21002FB06
J 0
(-1710 -275);
DISPLAY 0.638298 (-1710 -275);
DISPLAY INVISIBLE (-1710 -275);
FORCEADD VCC_CORE..1
(-1750 75);
FORCEPROP 3 LASTPIN (-1750 25) SIG_NAME PVDD11_S3_P0\g
J 0
(-1740 35);
DISPLAY 0.659574 (-1740 35);
PAINT MONO (-1740 35);
DISPLAY INVISIBLE (-1740 35);
FORCEPROP 1 LAST HDL_POWER PVDD11_S3_P0
J 1
(-1750 125);
DISPLAY 0.489362 (-1750 125);
PAINT GREEN (-1750 125);
FORCEPROP 2 LAST CDS_LIB pure_quanta_power
J 0
(-1750 75);
DISPLAY INVISIBLE (-1750 75);
FORCEPROP 1 LAST PATH I74
J 0
(-1700 100);
DISPLAY 0.872340 (-1700 100);
PAINT AQUA (-1700 100);
DISPLAY INVISIBLE (-1700 100);
FORCEADD OFFPAGE..5
(-2475 -400);
FORCEPROP 2 LAST $XR0 160 
J 0
(-2730 -400);
DISPLAY 0.638298 (-2730 -400);
PAINT MONO (-2730 -400);
FORCEPROP 2 LAST CDS_LIB standard
J 0
(-2475 -400);
DISPLAY INVISIBLE (-2475 -400);
FORCEPROP 1 LAST OFFPAGE TRUE
J 0
(-2150 -525);
DISPLAY 0.872340 (-2150 -525);
PAINT GREEN (-2150 -525);
DISPLAY INVISIBLE (-2150 -525);
FORCEPROP 1 LAST COMMENT_BODY TRUE
J 0
(-2375 -475);
DISPLAY 0.872340 (-2375 -475);
PAINT GREEN (-2375 -475);
DISPLAY INVISIBLE (-2375 -475);
FORCEPROP 2 LAST PATH I75
J 0
(-2425 -325);
DISPLAY 0.680851 (-2425 -325);
DISPLAY INVISIBLE (-2425 -325);
FORCEADD OFFPAGE..5
(-2475 -350);
FORCEPROP 2 LAST $XR0 160 
J 0
(-2730 -350);
DISPLAY 0.638298 (-2730 -350);
PAINT MONO (-2730 -350);
FORCEPROP 2 LAST CDS_LIB standard
J 0
(-2475 -350);
DISPLAY INVISIBLE (-2475 -350);
FORCEPROP 1 LAST OFFPAGE TRUE
J 0
(-2150 -475);
DISPLAY 0.872340 (-2150 -475);
PAINT GREEN (-2150 -475);
DISPLAY INVISIBLE (-2150 -475);
FORCEPROP 1 LAST COMMENT_BODY TRUE
J 0
(-2375 -425);
DISPLAY 0.872340 (-2375 -425);
PAINT GREEN (-2375 -425);
DISPLAY INVISIBLE (-2375 -425);
FORCEPROP 2 LAST PATH I76
J 0
(-2425 -275);
DISPLAY 0.680851 (-2425 -275);
DISPLAY INVISIBLE (-2425 -275);
FORCEADD VCC_CORE..1
(-2000 125);
FORCEPROP 3 LASTPIN (-2000 75) SIG_NAME PVDD11_S3_P0\g
J 0
(-1990 85);
DISPLAY 0.659574 (-1990 85);
PAINT MONO (-1990 85);
DISPLAY INVISIBLE (-1990 85);
FORCEPROP 1 LAST HDL_POWER PVDD11_S3_P0
J 1
(-2000 175);
DISPLAY 0.489362 (-2000 175);
PAINT GREEN (-2000 175);
FORCEPROP 2 LAST CDS_LIB pure_quanta_power
J 0
(-2000 125);
DISPLAY INVISIBLE (-2000 125);
FORCEPROP 1 LAST PATH I77
J 0
(-1950 150);
DISPLAY 0.872340 (-1950 150);
PAINT AQUA (-1950 150);
DISPLAY INVISIBLE (-1950 150);
FORCEADD Q_RES..2
(-2000 -100);
FORCEPROP 1 LAST LOCATION R290
J 0
(-1980 25);
DISPLAY 0.638298 (-1980 25);
FORCEPROP 0 LAST $SEC 1
J 0
(-1975 75);
DISPLAY 0.680851 (-1975 75);
PAINT MONO (-1975 75);
DISPLAY INVISIBLE (-1975 75);
FORCEPROP 0 LAST CDS_SEC 1
J 0
(-1975 75);
DISPLAY 0.680851 (-1975 75);
DISPLAY INVISIBLE (-1975 75);
FORCEPROP 1 LASTPIN (-2000 0) $PN 1
J 0
(-1995 -38);
DISPLAY 0.787234 (-1995 -38);
PAINT MONO (-1995 -38);
FORCEPROP 1 LASTPIN (-2000 -200) $PN 2
J 0
(-1995 -190);
DISPLAY 0.787234 (-1995 -190);
PAINT MONO (-1995 -190);
FORCEPROP 1 LAST TOLERANCE 1%
J 0
(-1980 -75);
DISPLAY 0.404255 (-1980 -75);
FORCEPROP 1 LAST VALUE 1K
J 0
(-1980 -25);
DISPLAY 0.404255 (-1980 -25);
FORCEPROP 1 LAST MATERIAL EMPTY
J 0
(-1985 -175);
DISPLAY 0.404255 (-1985 -175);
PAINT RED (-1985 -175);
FORCEPROP 1 LAST WATTAGE 1/16W
J 0
(-1985 -125);
DISPLAY 0.404255 (-1985 -125);
FORCEPROP 1 LAST PACK_TYPE 0402LF
J 0
(-1975 -225);
DISPLAY 0.404255 (-1975 -225);
FORCEPROP 2 LAST CDS_LIB pure_quanta
J 0
(-2000 -100);
DISPLAY INVISIBLE (-2000 -100);
FORCEPROP 1 LAST PATH I78
J 0
(-1950 75);
DISPLAY 0.978723 (-1950 75);
PAINT WHITE (-1950 75);
DISPLAY INVISIBLE (-1950 75);
FORCEPROP 1 LAST PART_NUMBER CS21002FB06
J 0
(-1960 -225);
DISPLAY 0.638298 (-1960 -225);
DISPLAY INVISIBLE (-1960 -225);
FORCEADD Q_RES..1
(-7750 800);
FORCEPROP 1 LAST LOCATION R151
J 0
(-7950 800);
DISPLAY 0.787234 (-7950 800);
FORCEPROP 0 LAST $SEC 1
J 0
(-7825 875);
DISPLAY 0.680851 (-7825 875);
PAINT MONO (-7825 875);
DISPLAY INVISIBLE (-7825 875);
FORCEPROP 0 LAST CDS_SEC 1
J 0
(-7825 875);
DISPLAY 0.680851 (-7825 875);
DISPLAY INVISIBLE (-7825 875);
FORCEPROP 1 LASTPIN (-7850 800) $PN 1
J 0
(-7838 812);
DISPLAY 0.787234 (-7838 812);
PAINT MONO (-7838 812);
FORCEPROP 1 LASTPIN (-7650 800) $PN 2
J 0
(-7688 812);
DISPLAY 0.787234 (-7688 812);
PAINT MONO (-7688 812);
FORCEPROP 1 LAST MATERIAL CHIP
J 0
(-7500 800);
DISPLAY 0.638298 (-7500 800);
FORCEPROP 1 LAST VALUE 0
J 2
(-7550 800);
DISPLAY 0.638298 (-7550 800);
FORCEPROP 1 LAST PACK_TYPE 0402LF
J 0
(-7825 825);
DISPLAY 0.638298 (-7825 825);
FORCEPROP 2 LAST CDS_LIB pure_quanta
J 0
(-7750 800);
DISPLAY INVISIBLE (-7750 800);
FORCEPROP 1 LAST WATTAGE 1/16W
J 2
(-7775 650);
DISPLAY 0.978723 (-7775 650);
DISPLAY INVISIBLE (-7775 650);
FORCEPROP 1 LAST TOLERANCE 5%
J 0
(-7775 700);
DISPLAY 0.978723 (-7775 700);
DISPLAY INVISIBLE (-7775 700);
FORCEPROP 1 LAST PATH I79
J 0
(-7800 950);
DISPLAY 0.978723 (-7800 950);
PAINT WHITE (-7800 950);
DISPLAY INVISIBLE (-7800 950);
FORCEPROP 1 LAST PART_NUMBER CS00002JB13
J 0
(-7625 825);
DISPLAY 0.978723 (-7625 825);
DISPLAY INVISIBLE (-7625 825);
FORCEADD Q_CAP..1
(-5125 -1175);
FORCEPROP 1 LAST LOCATION C612
J 0
(-5075 -1025);
DISPLAY 0.489362 (-5075 -1025);
PAINT SKYBLUE (-5075 -1025);
FORCEPROP 2 LAST $SEC 1
J 0
(-5075 -975);
DISPLAY 0.680851 (-5075 -975);
PAINT MONO (-5075 -975);
DISPLAY INVISIBLE (-5075 -975);
FORCEPROP 2 LAST CDS_SEC 1
J 0
(-5075 -975);
DISPLAY 0.680851 (-5075 -975);
DISPLAY INVISIBLE (-5075 -975);
FORCEPROP 1 LASTPIN (-5125 -1075) $PN 1
J 0
(-5115 -1095);
DISPLAY 0.489362 (-5115 -1095);
PAINT MONO (-5115 -1095);
FORCEPROP 1 LASTPIN (-5125 -1275) $PN 2
J 0
(-5115 -1295);
DISPLAY 0.489362 (-5115 -1295);
PAINT MONO (-5115 -1295);
FORCEPROP 1 LAST VALUE 0.1UF
J 0
(-5075 -1075);
DISPLAY 0.489362 (-5075 -1075);
PAINT SKYBLUE (-5075 -1075);
FORCEPROP 1 LAST MATERIAL X7R
J 0
(-5075 -1225);
DISPLAY 0.489362 (-5075 -1225);
PAINT SKYBLUE (-5075 -1225);
FORCEPROP 1 LAST TOLERANCE 10%
J 0
(-5075 -1175);
DISPLAY 0.489362 (-5075 -1175);
PAINT SKYBLUE (-5075 -1175);
FORCEPROP 1 LAST PACK_TYPE 0402
J 0
(-5075 -1275);
DISPLAY 0.489362 (-5075 -1275);
PAINT SKYBLUE (-5075 -1275);
FORCEPROP 1 LAST VOLTAGE 25V
J 0
(-5075 -1125);
DISPLAY 0.489362 (-5075 -1125);
PAINT SKYBLUE (-5075 -1125);
FORCEPROP 2 LAST CDS_LIB pure_quanta
J 0
(-5125 -1175);
DISPLAY INVISIBLE (-5125 -1175);
FORCEPROP 1 LAST PATH I8
J 0
(-5075 -1025);
DISPLAY 0.978723 (-5075 -1025);
PAINT WHITE (-5075 -1025);
DISPLAY INVISIBLE (-5075 -1025);
FORCEPROP 1 LAST PART_NUMBER CH4104K1B00
J 0
(-5075 -1325);
DISPLAY 0.489362 (-5075 -1325);
PAINT SKYBLUE (-5075 -1325);
DISPLAY INVISIBLE (-5075 -1325);
FORCEADD Q_RES..1
(-7750 700);
FORCEPROP 1 LAST LOCATION R162
J 0
(-7950 725);
DISPLAY 0.787234 (-7950 725);
FORCEPROP 0 LAST $SEC 1
J 0
(-7825 775);
DISPLAY 0.680851 (-7825 775);
PAINT MONO (-7825 775);
DISPLAY INVISIBLE (-7825 775);
FORCEPROP 0 LAST CDS_SEC 1
J 0
(-7825 775);
DISPLAY 0.680851 (-7825 775);
DISPLAY INVISIBLE (-7825 775);
FORCEPROP 1 LASTPIN (-7850 700) $PN 1
J 0
(-7838 712);
DISPLAY 0.787234 (-7838 712);
PAINT MONO (-7838 712);
FORCEPROP 1 LASTPIN (-7650 700) $PN 2
J 0
(-7688 712);
DISPLAY 0.787234 (-7688 712);
PAINT MONO (-7688 712);
FORCEPROP 1 LAST VALUE 0
J 2
(-7550 700);
DISPLAY 0.638298 (-7550 700);
FORCEPROP 1 LAST PACK_TYPE 0402LF
J 0
(-7825 725);
DISPLAY 0.638298 (-7825 725);
FORCEPROP 1 LAST MATERIAL CHIP
J 0
(-7500 700);
DISPLAY 0.638298 (-7500 700);
FORCEPROP 2 LAST CDS_LIB pure_quanta
J 0
(-7750 700);
DISPLAY INVISIBLE (-7750 700);
FORCEPROP 1 LAST TOLERANCE 5%
J 0
(-7775 600);
DISPLAY 0.978723 (-7775 600);
DISPLAY INVISIBLE (-7775 600);
FORCEPROP 1 LAST WATTAGE 1/16W
J 2
(-7775 550);
DISPLAY 0.978723 (-7775 550);
DISPLAY INVISIBLE (-7775 550);
FORCEPROP 1 LAST PATH I80
J 0
(-7800 850);
DISPLAY 0.978723 (-7800 850);
PAINT WHITE (-7800 850);
DISPLAY INVISIBLE (-7800 850);
FORCEPROP 1 LAST PART_NUMBER CS00002JB13
J 0
(-7625 725);
DISPLAY 0.978723 (-7625 725);
DISPLAY INVISIBLE (-7625 725);
FORCEADD OFFPAGE..3
R 2
(-8825 700);
FORCEPROP 2 LAST $XR2 160 
J 0
(-9345 700);
DISPLAY 0.638298 (-9345 700);
PAINT MONO (-9345 700);
FORCEPROP 2 LAST $XR1 151 
J 0
(-9225 700);
DISPLAY 0.638298 (-9225 700);
PAINT MONO (-9225 700);
FORCEPROP 2 LAST $XR0 150 
J 0
(-9105 700);
DISPLAY 0.638298 (-9105 700);
PAINT MONO (-9105 700);
FORCEPROP 2 LAST CDS_LIB standard
J 0
(-8825 700);
DISPLAY INVISIBLE (-8825 700);
FORCEPROP 1 LAST OFFPAGE TRUE
J 2
(-9150 575);
DISPLAY 0.872340 (-9150 575);
PAINT GREEN (-9150 575);
DISPLAY INVISIBLE (-9150 575);
FORCEPROP 1 LAST COMMENT_BODY TRUE
J 2
(-8775 600);
DISPLAY 0.872340 (-8775 600);
PAINT GREEN (-8775 600);
DISPLAY INVISIBLE (-8775 600);
FORCEPROP 2 LAST PATH I81
J 0
(-8775 775);
DISPLAY 0.680851 (-8775 775);
DISPLAY INVISIBLE (-8775 775);
FORCEADD OFFPAGE..1
(-8825 800);
FORCEPROP 2 LAST $XR2 160 
J 0
(-9317 800);
DISPLAY 0.638298 (-9317 800);
PAINT MONO (-9317 800);
FORCEPROP 2 LAST $XR1 151 
J 0
(-9197 800);
DISPLAY 0.638298 (-9197 800);
PAINT MONO (-9197 800);
FORCEPROP 2 LAST $XR0 150 
J 0
(-9077 800);
DISPLAY 0.638298 (-9077 800);
PAINT MONO (-9077 800);
FORCEPROP 2 LAST CDS_LIB standard
J 0
(-8825 800);
DISPLAY INVISIBLE (-8825 800);
FORCEPROP 1 LAST OFFPAGE TRUE
J 0
(-8500 675);
DISPLAY 0.872340 (-8500 675);
PAINT GREEN (-8500 675);
DISPLAY INVISIBLE (-8500 675);
FORCEPROP 1 LAST COMMENT_BODY TRUE
J 0
(-8700 700);
DISPLAY 0.872340 (-8700 700);
PAINT GREEN (-8700 700);
DISPLAY INVISIBLE (-8700 700);
FORCEPROP 2 LAST PATH I82
J 0
(-8775 875);
DISPLAY 0.680851 (-8775 875);
DISPLAY INVISIBLE (-8775 875);
FORCEADD OFFPAGE..1
(-8750 2350);
FORCEPROP 2 LAST $XR2 160 
J 0
(-9272 2350);
DISPLAY 0.638298 (-9272 2350);
PAINT MONO (-9272 2350);
FORCEPROP 2 LAST $XR1 151 
J 0
(-9152 2350);
DISPLAY 0.638298 (-9152 2350);
PAINT MONO (-9152 2350);
FORCEPROP 2 LAST $XR0 150 
J 0
(-9032 2350);
DISPLAY 0.638298 (-9032 2350);
PAINT MONO (-9032 2350);
FORCEPROP 2 LAST CDS_LIB standard
J 0
(-8750 2350);
DISPLAY INVISIBLE (-8750 2350);
FORCEPROP 1 LAST OFFPAGE TRUE
J 0
(-8425 2225);
DISPLAY 0.872340 (-8425 2225);
PAINT GREEN (-8425 2225);
DISPLAY INVISIBLE (-8425 2225);
FORCEPROP 1 LAST COMMENT_BODY TRUE
J 0
(-8625 2250);
DISPLAY 0.872340 (-8625 2250);
PAINT GREEN (-8625 2250);
DISPLAY INVISIBLE (-8625 2250);
FORCEPROP 2 LAST PATH I83
J 0
(-9000 2400);
DISPLAY 0.680851 (-9000 2400);
DISPLAY INVISIBLE (-9000 2400);
FORCEADD OFFPAGE..3
R 2
(-8750 2250);
FORCEPROP 2 LAST $XR2 160 
J 0
(-9270 2250);
DISPLAY 0.638298 (-9270 2250);
PAINT MONO (-9270 2250);
FORCEPROP 2 LAST $XR1 151 
J 0
(-9150 2250);
DISPLAY 0.638298 (-9150 2250);
PAINT MONO (-9150 2250);
FORCEPROP 2 LAST $XR0 150 
J 0
(-9030 2250);
DISPLAY 0.638298 (-9030 2250);
PAINT MONO (-9030 2250);
FORCEPROP 2 LAST CDS_LIB standard
J 0
(-8750 2250);
DISPLAY INVISIBLE (-8750 2250);
FORCEPROP 1 LAST OFFPAGE TRUE
J 2
(-9075 2125);
DISPLAY 0.872340 (-9075 2125);
PAINT GREEN (-9075 2125);
DISPLAY INVISIBLE (-9075 2125);
FORCEPROP 1 LAST COMMENT_BODY TRUE
J 2
(-8700 2150);
DISPLAY 0.872340 (-8700 2150);
PAINT GREEN (-8700 2150);
DISPLAY INVISIBLE (-8700 2150);
FORCEPROP 2 LAST PATH I84
J 0
(-9025 2300);
DISPLAY 0.680851 (-9025 2300);
DISPLAY INVISIBLE (-9025 2300);
FORCEADD OFFPAGE..1
(-3225 2700);
FORCEPROP 2 LAST $XR0 160 
J 0
(-3477 2700);
DISPLAY 0.638298 (-3477 2700);
PAINT MONO (-3477 2700);
FORCEPROP 2 LAST CDS_LIB standard
J 0
(-3225 2700);
DISPLAY INVISIBLE (-3225 2700);
FORCEPROP 1 LAST OFFPAGE TRUE
J 0
(-2900 2575);
DISPLAY 0.872340 (-2900 2575);
PAINT GREEN (-2900 2575);
DISPLAY INVISIBLE (-2900 2575);
FORCEPROP 1 LAST COMMENT_BODY TRUE
J 0
(-3100 2600);
DISPLAY 0.872340 (-3100 2600);
PAINT GREEN (-3100 2600);
DISPLAY INVISIBLE (-3100 2600);
FORCEPROP 2 LAST PATH I87
J 0
(-3175 2775);
DISPLAY 0.680851 (-3175 2775);
DISPLAY INVISIBLE (-3175 2775);
FORCEADD OFFPAGE..1
(-3200 2075);
FORCEPROP 2 LAST $XR0 160 
J 0
(-3452 2075);
DISPLAY 0.638298 (-3452 2075);
PAINT MONO (-3452 2075);
FORCEPROP 2 LAST CDS_LIB standard
J 0
(-3200 2075);
DISPLAY INVISIBLE (-3200 2075);
FORCEPROP 1 LAST OFFPAGE TRUE
J 0
(-2875 1950);
DISPLAY 0.872340 (-2875 1950);
PAINT GREEN (-2875 1950);
DISPLAY INVISIBLE (-2875 1950);
FORCEPROP 1 LAST COMMENT_BODY TRUE
J 0
(-3075 1975);
DISPLAY 0.872340 (-3075 1975);
PAINT GREEN (-3075 1975);
DISPLAY INVISIBLE (-3075 1975);
FORCEPROP 2 LAST PATH I88
J 0
(-3150 2150);
DISPLAY 0.680851 (-3150 2150);
DISPLAY INVISIBLE (-3150 2150);
FORCEADD OFFPAGE..1
(-2850 1075);
FORCEPROP 2 LAST $XR0 160 
J 0
(-3102 1075);
DISPLAY 0.638298 (-3102 1075);
PAINT MONO (-3102 1075);
FORCEPROP 2 LAST CDS_LIB standard
J 0
(-2850 1075);
DISPLAY INVISIBLE (-2850 1075);
FORCEPROP 1 LAST OFFPAGE TRUE
J 0
(-2525 950);
DISPLAY 0.872340 (-2525 950);
PAINT GREEN (-2525 950);
DISPLAY INVISIBLE (-2525 950);
FORCEPROP 1 LAST COMMENT_BODY TRUE
J 0
(-2725 975);
DISPLAY 0.872340 (-2725 975);
PAINT GREEN (-2725 975);
DISPLAY INVISIBLE (-2725 975);
FORCEPROP 2 LAST PATH I89
J 0
(-2800 1150);
DISPLAY 0.680851 (-2800 1150);
DISPLAY INVISIBLE (-2800 1150);
FORCEADD UNIVERSAL_GND..1
(-5125 -1375);
FORCEPROP 3 LASTPIN (-5125 -1325) SIG_NAME GND\g
J 0
(-5115 -1315);
DISPLAY 0.659574 (-5115 -1315);
PAINT MONO (-5115 -1315);
DISPLAY INVISIBLE (-5115 -1315);
FORCEPROP 2 LAST CDS_LIB pure_quanta_power
J 0
(-5125 -1375);
DISPLAY INVISIBLE (-5125 -1375);
FORCEPROP 1 LAST HDL_POWER GND
J 1
(-5100 -1450);
DISPLAY 0.872340 (-5100 -1450);
PAINT GREEN (-5100 -1450);
DISPLAY INVISIBLE (-5100 -1450);
FORCEPROP 1 LAST PATH I9
J 0
(-5050 -1375);
DISPLAY 0.872340 (-5050 -1375);
PAINT AQUA (-5050 -1375);
DISPLAY INVISIBLE (-5050 -1375);
FORCEADD OFFPAGE..1
(-2875 475);
FORCEPROP 2 LAST $XR0 160 
J 0
(-3127 475);
DISPLAY 0.638298 (-3127 475);
PAINT MONO (-3127 475);
FORCEPROP 2 LAST CDS_LIB standard
J 0
(-2875 475);
DISPLAY INVISIBLE (-2875 475);
FORCEPROP 1 LAST OFFPAGE TRUE
J 0
(-2550 350);
DISPLAY 0.872340 (-2550 350);
PAINT GREEN (-2550 350);
DISPLAY INVISIBLE (-2550 350);
FORCEPROP 1 LAST COMMENT_BODY TRUE
J 0
(-2750 375);
DISPLAY 0.872340 (-2750 375);
PAINT GREEN (-2750 375);
DISPLAY INVISIBLE (-2750 375);
FORCEPROP 2 LAST PATH I90
J 0
(-2825 550);
DISPLAY 0.680851 (-2825 550);
DISPLAY INVISIBLE (-2825 550);
FORCEADD Q_RES..1
(-2725 2250);
FORCEPROP 1 LAST LOCATION R257
J 0
(-2825 2175);
DISPLAY 0.978723 (-2825 2175);
FORCEPROP 0 LAST $SEC 1
J 0
(-2450 2275);
DISPLAY 0.680851 (-2450 2275);
PAINT MONO (-2450 2275);
DISPLAY INVISIBLE (-2450 2275);
FORCEPROP 0 LAST CDS_SEC 1
J 0
(-2450 2275);
DISPLAY 0.680851 (-2450 2275);
DISPLAY INVISIBLE (-2450 2275);
FORCEPROP 1 LASTPIN (-2825 2250) $PN 1
J 0
(-2813 2262);
DISPLAY 0.787234 (-2813 2262);
PAINT MONO (-2813 2262);
FORCEPROP 1 LASTPIN (-2625 2250) $PN 2
J 0
(-2663 2262);
DISPLAY 0.787234 (-2663 2262);
PAINT MONO (-2663 2262);
FORCEPROP 1 LAST VALUE 0
J 2
(-2525 2250);
DISPLAY 0.489362 (-2525 2250);
PAINT SKYBLUE (-2525 2250);
FORCEPROP 1 LAST MATERIAL EMPTY
J 0
(-2450 2250);
DISPLAY 0.489362 (-2450 2250);
PAINT RED (-2450 2250);
FORCEPROP 1 LAST PACK_TYPE 0402LF
J 0
(-2675 2175);
DISPLAY 0.489362 (-2675 2175);
PAINT SKYBLUE (-2675 2175);
DISPLAY INVISIBLE (-2675 2175);
FORCEPROP 1 LAST TOLERANCE 5%
J 0
(-2750 2175);
DISPLAY 0.489362 (-2750 2175);
PAINT SKYBLUE (-2750 2175);
DISPLAY INVISIBLE (-2750 2175);
FORCEPROP 1 LAST WATTAGE 1/16W
J 2
(-2325 2175);
DISPLAY 0.489362 (-2325 2175);
PAINT SKYBLUE (-2325 2175);
DISPLAY INVISIBLE (-2325 2175);
FORCEPROP 2 LAST CDS_LIB pure_quanta
J 0
(-2725 2250);
DISPLAY INVISIBLE (-2725 2250);
FORCEPROP 1 LAST PATH I91
J 0
(-2775 2400);
DISPLAY 0.978723 (-2775 2400);
PAINT WHITE (-2775 2400);
DISPLAY INVISIBLE (-2775 2400);
FORCEPROP 1 LAST PART_NUMBER CS00002JB13
J 0
(-2700 2300);
DISPLAY 0.489362 (-2700 2300);
PAINT SKYBLUE (-2700 2300);
DISPLAY INVISIBLE (-2700 2300);
FORCEADD Q_RES..1
(-2750 2350);
FORCEPROP 1 LAST LOCATION R256
J 0
(-2825 2400);
DISPLAY 0.978723 (-2825 2400);
FORCEPROP 0 LAST $SEC 1
J 0
(-2825 2450);
DISPLAY 0.680851 (-2825 2450);
PAINT MONO (-2825 2450);
DISPLAY INVISIBLE (-2825 2450);
FORCEPROP 0 LAST CDS_SEC 1
J 0
(-2825 2450);
DISPLAY 0.680851 (-2825 2450);
DISPLAY INVISIBLE (-2825 2450);
FORCEPROP 1 LASTPIN (-2850 2350) $PN 1
J 0
(-2838 2362);
DISPLAY 0.787234 (-2838 2362);
PAINT MONO (-2838 2362);
FORCEPROP 1 LASTPIN (-2650 2350) $PN 2
J 0
(-2688 2362);
DISPLAY 0.787234 (-2688 2362);
PAINT MONO (-2688 2362);
FORCEPROP 1 LAST VALUE 0
J 2
(-2550 2350);
DISPLAY 0.489362 (-2550 2350);
PAINT SKYBLUE (-2550 2350);
FORCEPROP 1 LAST MATERIAL EMPTY
J 0
(-2475 2350);
DISPLAY 0.489362 (-2475 2350);
PAINT RED (-2475 2350);
FORCEPROP 1 LAST WATTAGE 1/16W
J 2
(-2350 2275);
DISPLAY 0.489362 (-2350 2275);
PAINT SKYBLUE (-2350 2275);
DISPLAY INVISIBLE (-2350 2275);
FORCEPROP 1 LAST TOLERANCE 5%
J 0
(-2775 2275);
DISPLAY 0.489362 (-2775 2275);
PAINT SKYBLUE (-2775 2275);
DISPLAY INVISIBLE (-2775 2275);
FORCEPROP 1 LAST PACK_TYPE 0402LF
J 0
(-2700 2275);
DISPLAY 0.489362 (-2700 2275);
PAINT SKYBLUE (-2700 2275);
DISPLAY INVISIBLE (-2700 2275);
FORCEPROP 2 LAST CDS_LIB pure_quanta
J 0
(-2750 2350);
DISPLAY INVISIBLE (-2750 2350);
FORCEPROP 1 LAST PATH I92
J 0
(-2800 2500);
DISPLAY 0.978723 (-2800 2500);
PAINT WHITE (-2800 2500);
DISPLAY INVISIBLE (-2800 2500);
FORCEPROP 1 LAST PART_NUMBER CS00002JB13
J 0
(-2725 2400);
DISPLAY 0.489362 (-2725 2400);
PAINT SKYBLUE (-2725 2400);
DISPLAY INVISIBLE (-2725 2400);
FORCEADD Q_RES..1
(-4100 2350);
FORCEPROP 1 LAST LOCATION R1151
J 0
(-4175 2400);
DISPLAY 0.978723 (-4175 2400);
FORCEPROP 0 LAST $SEC 1
J 0
(-4175 2450);
DISPLAY 0.680851 (-4175 2450);
PAINT MONO (-4175 2450);
DISPLAY INVISIBLE (-4175 2450);
FORCEPROP 0 LAST CDS_SEC 1
J 0
(-4175 2450);
DISPLAY 0.680851 (-4175 2450);
DISPLAY INVISIBLE (-4175 2450);
FORCEPROP 1 LASTPIN (-4200 2350) $PN 1
J 0
(-4188 2362);
DISPLAY 0.787234 (-4188 2362);
PAINT MONO (-4188 2362);
FORCEPROP 1 LASTPIN (-4000 2350) $PN 2
J 0
(-4038 2362);
DISPLAY 0.787234 (-4038 2362);
PAINT MONO (-4038 2362);
FORCEPROP 1 LAST VALUE 0
J 2
(-3900 2350);
DISPLAY 0.489362 (-3900 2350);
PAINT SKYBLUE (-3900 2350);
FORCEPROP 1 LAST MATERIAL EMPTY
J 0
(-4325 2350);
DISPLAY 0.489362 (-4325 2350);
PAINT RED (-4325 2350);
FORCEPROP 2 LAST CDS_LIB pure_quanta
J 0
(-4100 2350);
DISPLAY INVISIBLE (-4100 2350);
FORCEPROP 1 LAST WATTAGE 1/16W
J 2
(-3700 2275);
DISPLAY 0.489362 (-3700 2275);
PAINT SKYBLUE (-3700 2275);
DISPLAY INVISIBLE (-3700 2275);
FORCEPROP 1 LAST TOLERANCE 5%
J 0
(-4125 2275);
DISPLAY 0.489362 (-4125 2275);
PAINT SKYBLUE (-4125 2275);
DISPLAY INVISIBLE (-4125 2275);
FORCEPROP 1 LAST PACK_TYPE 0402LF
J 0
(-4050 2275);
DISPLAY 0.489362 (-4050 2275);
PAINT SKYBLUE (-4050 2275);
DISPLAY INVISIBLE (-4050 2275);
FORCEPROP 1 LAST PATH I93
J 0
(-4150 2500);
DISPLAY 0.978723 (-4150 2500);
PAINT WHITE (-4150 2500);
DISPLAY INVISIBLE (-4150 2500);
FORCEPROP 1 LAST PART_NUMBER CS00002JB13
J 0
(-4075 2400);
DISPLAY 0.489362 (-4075 2400);
PAINT SKYBLUE (-4075 2400);
DISPLAY INVISIBLE (-4075 2400);
FORCEADD Q_RES..1
(-4100 2250);
FORCEPROP 1 LAST LOCATION R1152
J 0
(-4200 2175);
DISPLAY 0.978723 (-4200 2175);
FORCEPROP 0 LAST $SEC 1
J 0
(-3900 2275);
DISPLAY 0.680851 (-3900 2275);
PAINT MONO (-3900 2275);
DISPLAY INVISIBLE (-3900 2275);
FORCEPROP 0 LAST CDS_SEC 1
J 0
(-3900 2275);
DISPLAY 0.680851 (-3900 2275);
DISPLAY INVISIBLE (-3900 2275);
FORCEPROP 1 LASTPIN (-4200 2250) $PN 1
J 0
(-4188 2262);
DISPLAY 0.787234 (-4188 2262);
PAINT MONO (-4188 2262);
FORCEPROP 1 LASTPIN (-4000 2250) $PN 2
J 0
(-4038 2262);
DISPLAY 0.787234 (-4038 2262);
PAINT MONO (-4038 2262);
FORCEPROP 1 LAST MATERIAL EMPTY
J 0
(-4325 2250);
DISPLAY 0.489362 (-4325 2250);
PAINT RED (-4325 2250);
FORCEPROP 1 LAST VALUE 0
J 2
(-3900 2250);
DISPLAY 0.489362 (-3900 2250);
PAINT SKYBLUE (-3900 2250);
FORCEPROP 2 LAST CDS_LIB pure_quanta
J 0
(-4100 2250);
DISPLAY INVISIBLE (-4100 2250);
FORCEPROP 1 LAST PACK_TYPE 0402LF
J 0
(-4050 2175);
DISPLAY 0.489362 (-4050 2175);
PAINT SKYBLUE (-4050 2175);
DISPLAY INVISIBLE (-4050 2175);
FORCEPROP 1 LAST TOLERANCE 5%
J 0
(-4125 2175);
DISPLAY 0.489362 (-4125 2175);
PAINT SKYBLUE (-4125 2175);
DISPLAY INVISIBLE (-4125 2175);
FORCEPROP 1 LAST WATTAGE 1/16W
J 2
(-3700 2175);
DISPLAY 0.489362 (-3700 2175);
PAINT SKYBLUE (-3700 2175);
DISPLAY INVISIBLE (-3700 2175);
FORCEPROP 1 LAST PATH I94
J 0
(-4150 2400);
DISPLAY 0.978723 (-4150 2400);
PAINT WHITE (-4150 2400);
DISPLAY INVISIBLE (-4150 2400);
FORCEPROP 1 LAST PART_NUMBER CS00002JB13
J 0
(-4075 2300);
DISPLAY 0.489362 (-4075 2300);
PAINT SKYBLUE (-4075 2300);
DISPLAY INVISIBLE (-4075 2300);
FORCEADD Q_RES..1
(-5975 3325);
FORCEPROP 1 LAST LOCATION R790
J 0
(-6075 3250);
DISPLAY 0.978723 (-6075 3250);
FORCEPROP 0 LAST $SEC 1
J 0
(-5775 3350);
DISPLAY 0.680851 (-5775 3350);
PAINT MONO (-5775 3350);
DISPLAY INVISIBLE (-5775 3350);
FORCEPROP 0 LAST CDS_SEC 1
J 0
(-5775 3350);
DISPLAY 0.680851 (-5775 3350);
DISPLAY INVISIBLE (-5775 3350);
FORCEPROP 1 LASTPIN (-6075 3325) $PN 1
J 0
(-6063 3337);
DISPLAY 0.787234 (-6063 3337);
PAINT MONO (-6063 3337);
FORCEPROP 1 LASTPIN (-5875 3325) $PN 2
J 0
(-5913 3337);
DISPLAY 0.787234 (-5913 3337);
PAINT MONO (-5913 3337);
FORCEPROP 1 LAST VALUE 0
J 2
(-5775 3325);
DISPLAY 0.489362 (-5775 3325);
PAINT SKYBLUE (-5775 3325);
FORCEPROP 1 LAST MATERIAL EMPTY
J 0
(-6200 3325);
DISPLAY 0.489362 (-6200 3325);
PAINT RED (-6200 3325);
FORCEPROP 1 LAST PACK_TYPE 0402LF
J 0
(-5925 3250);
DISPLAY 0.489362 (-5925 3250);
PAINT SKYBLUE (-5925 3250);
DISPLAY INVISIBLE (-5925 3250);
FORCEPROP 1 LAST TOLERANCE 5%
J 0
(-6000 3250);
DISPLAY 0.489362 (-6000 3250);
PAINT SKYBLUE (-6000 3250);
DISPLAY INVISIBLE (-6000 3250);
FORCEPROP 1 LAST WATTAGE 1/16W
J 2
(-5575 3250);
DISPLAY 0.489362 (-5575 3250);
PAINT SKYBLUE (-5575 3250);
DISPLAY INVISIBLE (-5575 3250);
FORCEPROP 2 LAST CDS_LIB pure_quanta
J 0
(-5975 3325);
DISPLAY INVISIBLE (-5975 3325);
FORCEPROP 1 LAST PATH I95
J 0
(-6025 3475);
DISPLAY 0.978723 (-6025 3475);
PAINT WHITE (-6025 3475);
DISPLAY INVISIBLE (-6025 3475);
FORCEPROP 1 LAST PART_NUMBER CS00002JB13
J 0
(-5950 3375);
DISPLAY 0.489362 (-5950 3375);
PAINT SKYBLUE (-5950 3375);
DISPLAY INVISIBLE (-5950 3375);
FORCEADD Q_RES..1
(-5975 3375);
FORCEPROP 1 LAST LOCATION R789
J 0
(-6050 3425);
DISPLAY 0.978723 (-6050 3425);
FORCEPROP 0 LAST $SEC 1
J 0
(-6050 3475);
DISPLAY 0.680851 (-6050 3475);
PAINT MONO (-6050 3475);
DISPLAY INVISIBLE (-6050 3475);
FORCEPROP 0 LAST CDS_SEC 1
J 0
(-6050 3475);
DISPLAY 0.680851 (-6050 3475);
DISPLAY INVISIBLE (-6050 3475);
FORCEPROP 1 LASTPIN (-6075 3375) $PN 1
J 0
(-6063 3387);
DISPLAY 0.787234 (-6063 3387);
PAINT MONO (-6063 3387);
FORCEPROP 1 LASTPIN (-5875 3375) $PN 2
J 0
(-5913 3387);
DISPLAY 0.787234 (-5913 3387);
PAINT MONO (-5913 3387);
FORCEPROP 1 LAST VALUE 0
J 2
(-5775 3375);
DISPLAY 0.489362 (-5775 3375);
PAINT SKYBLUE (-5775 3375);
FORCEPROP 1 LAST MATERIAL EMPTY
J 0
(-6200 3375);
DISPLAY 0.489362 (-6200 3375);
PAINT RED (-6200 3375);
FORCEPROP 1 LAST WATTAGE 1/16W
J 2
(-5575 3300);
DISPLAY 0.489362 (-5575 3300);
PAINT SKYBLUE (-5575 3300);
DISPLAY INVISIBLE (-5575 3300);
FORCEPROP 1 LAST TOLERANCE 5%
J 0
(-6000 3300);
DISPLAY 0.489362 (-6000 3300);
PAINT SKYBLUE (-6000 3300);
DISPLAY INVISIBLE (-6000 3300);
FORCEPROP 1 LAST PACK_TYPE 0402LF
J 0
(-5925 3300);
DISPLAY 0.489362 (-5925 3300);
PAINT SKYBLUE (-5925 3300);
DISPLAY INVISIBLE (-5925 3300);
FORCEPROP 2 LAST CDS_LIB pure_quanta
J 0
(-5975 3375);
DISPLAY INVISIBLE (-5975 3375);
FORCEPROP 1 LAST PATH I96
J 0
(-6025 3525);
DISPLAY 0.978723 (-6025 3525);
PAINT WHITE (-6025 3525);
DISPLAY INVISIBLE (-6025 3525);
FORCEPROP 1 LAST PART_NUMBER CS00002JB13
J 0
(-5950 3425);
DISPLAY 0.489362 (-5950 3425);
PAINT SKYBLUE (-5950 3425);
DISPLAY INVISIBLE (-5950 3425);
FORCEADD Q_RES..1
(-7850 2250);
FORCEPROP 1 LAST LOCATION R150
J 0
(-7950 2175);
DISPLAY 0.978723 (-7950 2175);
FORCEPROP 0 LAST $SEC 1
J 0
(-7650 2275);
DISPLAY 0.680851 (-7650 2275);
PAINT MONO (-7650 2275);
DISPLAY INVISIBLE (-7650 2275);
FORCEPROP 0 LAST CDS_SEC 1
J 0
(-7650 2275);
DISPLAY 0.680851 (-7650 2275);
DISPLAY INVISIBLE (-7650 2275);
FORCEPROP 1 LASTPIN (-7950 2250) $PN 1
J 0
(-7938 2262);
DISPLAY 0.787234 (-7938 2262);
PAINT MONO (-7938 2262);
FORCEPROP 1 LASTPIN (-7750 2250) $PN 2
J 0
(-7788 2262);
DISPLAY 0.787234 (-7788 2262);
PAINT MONO (-7788 2262);
FORCEPROP 1 LAST VALUE 0
J 2
(-7650 2250);
DISPLAY 0.489362 (-7650 2250);
PAINT SKYBLUE (-7650 2250);
FORCEPROP 1 LAST MATERIAL EMPTY
J 0
(-8075 2250);
DISPLAY 0.489362 (-8075 2250);
PAINT RED (-8075 2250);
FORCEPROP 2 LAST CDS_LIB pure_quanta
J 0
(-7850 2250);
DISPLAY INVISIBLE (-7850 2250);
FORCEPROP 1 LAST PACK_TYPE 0402LF
J 0
(-7800 2175);
DISPLAY 0.489362 (-7800 2175);
PAINT SKYBLUE (-7800 2175);
DISPLAY INVISIBLE (-7800 2175);
FORCEPROP 1 LAST TOLERANCE 5%
J 0
(-7875 2175);
DISPLAY 0.489362 (-7875 2175);
PAINT SKYBLUE (-7875 2175);
DISPLAY INVISIBLE (-7875 2175);
FORCEPROP 1 LAST WATTAGE 1/16W
J 2
(-7450 2175);
DISPLAY 0.489362 (-7450 2175);
PAINT SKYBLUE (-7450 2175);
DISPLAY INVISIBLE (-7450 2175);
FORCEPROP 1 LAST PATH I97
J 0
(-7900 2400);
DISPLAY 0.978723 (-7900 2400);
PAINT WHITE (-7900 2400);
DISPLAY INVISIBLE (-7900 2400);
FORCEPROP 1 LAST PART_NUMBER CS00002JB13
J 0
(-7825 2300);
DISPLAY 0.489362 (-7825 2300);
PAINT SKYBLUE (-7825 2300);
DISPLAY INVISIBLE (-7825 2300);
FORCEADD Q_RES..1
(-7850 2350);
FORCEPROP 1 LAST LOCATION R140
J 0
(-7925 2400);
DISPLAY 0.978723 (-7925 2400);
FORCEPROP 0 LAST $SEC 1
J 0
(-7925 2450);
DISPLAY 0.680851 (-7925 2450);
PAINT MONO (-7925 2450);
DISPLAY INVISIBLE (-7925 2450);
FORCEPROP 0 LAST CDS_SEC 1
J 0
(-7925 2450);
DISPLAY 0.680851 (-7925 2450);
DISPLAY INVISIBLE (-7925 2450);
FORCEPROP 1 LASTPIN (-7950 2350) $PN 1
J 0
(-7938 2362);
DISPLAY 0.787234 (-7938 2362);
PAINT MONO (-7938 2362);
FORCEPROP 1 LASTPIN (-7750 2350) $PN 2
J 0
(-7788 2362);
DISPLAY 0.787234 (-7788 2362);
PAINT MONO (-7788 2362);
FORCEPROP 1 LAST VALUE 0
J 2
(-7650 2350);
DISPLAY 0.489362 (-7650 2350);
PAINT SKYBLUE (-7650 2350);
FORCEPROP 1 LAST MATERIAL EMPTY
J 0
(-8075 2350);
DISPLAY 0.489362 (-8075 2350);
PAINT RED (-8075 2350);
FORCEPROP 2 LAST CDS_LIB pure_quanta
J 0
(-7850 2350);
DISPLAY INVISIBLE (-7850 2350);
FORCEPROP 1 LAST WATTAGE 1/16W
J 2
(-7450 2275);
DISPLAY 0.489362 (-7450 2275);
PAINT SKYBLUE (-7450 2275);
DISPLAY INVISIBLE (-7450 2275);
FORCEPROP 1 LAST TOLERANCE 5%
J 0
(-7875 2275);
DISPLAY 0.489362 (-7875 2275);
PAINT SKYBLUE (-7875 2275);
DISPLAY INVISIBLE (-7875 2275);
FORCEPROP 1 LAST PACK_TYPE 0402LF
J 0
(-7800 2275);
DISPLAY 0.489362 (-7800 2275);
PAINT SKYBLUE (-7800 2275);
DISPLAY INVISIBLE (-7800 2275);
FORCEPROP 1 LAST PATH I98
J 0
(-7900 2500);
DISPLAY 0.978723 (-7900 2500);
PAINT WHITE (-7900 2500);
DISPLAY INVISIBLE (-7900 2500);
FORCEPROP 1 LAST PART_NUMBER CS00002JB13
J 0
(-7825 2400);
DISPLAY 0.489362 (-7825 2400);
PAINT SKYBLUE (-7825 2400);
DISPLAY INVISIBLE (-7825 2400);
FORCEADD PCA9617ADP..1
R 2
(-6000 750);
FORCEPROP 1 LAST LOCATION U2
J 2
(-5726 1160);
DISPLAY 0.723404 (-5726 1160);
PAINT GREEN (-5726 1160);
FORCEPROP 2 LAST SEC 1
J 2
(-5750 1300);
DISPLAY 0.680851 (-5750 1300);
PAINT MONO (-5750 1300);
DISPLAY INVISIBLE (-5750 1300);
FORCEPROP 2 LASTPIN (-6425 550) $PN 5
J 2
(-6435 560);
DISPLAY 0.680851 (-6435 560);
PAINT MONO (-6435 560);
FORCEPROP 2 LASTPIN (-5575 550) $PN 4
J 0
(-5565 560);
DISPLAY 0.680851 (-5565 560);
PAINT MONO (-5565 560);
FORCEPROP 2 LASTPIN (-5575 800) $PN 2
J 0
(-5565 810);
DISPLAY 0.680851 (-5565 810);
PAINT MONO (-5565 810);
FORCEPROP 2 LASTPIN (-6425 800) $PN 7
J 2
(-6435 810);
DISPLAY 0.680851 (-6435 810);
PAINT MONO (-6435 810);
FORCEPROP 2 LASTPIN (-5575 700) $PN 3
J 0
(-5565 710);
DISPLAY 0.680851 (-5565 710);
PAINT MONO (-5565 710);
FORCEPROP 2 LASTPIN (-6425 700) $PN 6
J 2
(-6435 710);
DISPLAY 0.680851 (-6435 710);
PAINT MONO (-6435 710);
FORCEPROP 2 LASTPIN (-5575 950) $PN 1
J 0
(-5565 960);
DISPLAY 0.680851 (-5565 960);
PAINT MONO (-5565 960);
FORCEPROP 2 LASTPIN (-6425 950) $PN 8
J 2
(-6435 960);
DISPLAY 0.680851 (-6435 960);
PAINT MONO (-6435 960);
FORCEPROP 2 LAST VALUE PCA9617ADP
J 2
(-5750 1200);
DISPLAY 0.680851 (-5750 1200);
FORCEPROP 1 LAST MATERIAL IC
J 2
(-5726 1055);
DISPLAY 0.723404 (-5726 1055);
PAINT GREEN (-5726 1055);
FORCEPROP 2 LAST PART_TYPE SMLF
J 2
(-5750 1250);
DISPLAY 0.680851 (-5750 1250);
FORCEPROP 1 LAST CDS_LMAN_SYM_OUTLINE -275,300,275,-300
J 2
(-6000 750);
DISPLAY 0.468085 (-6000 750);
PAINT GREEN (-6000 750);
DISPLAY INVISIBLE (-6000 750);
FORCEPROP 1 LAST NEEDS_NO_SIZE TRUE
J 2
(-6275 450);
DISPLAY 0.468085 (-6275 450);
PAINT GREEN (-6275 450);
DISPLAY INVISIBLE (-6275 450);
FORCEPROP 2 LAST CDS_LIB pure_quanta
J 2
(-6000 750);
DISPLAY INVISIBLE (-6000 750);
FORCEPROP 2 LAST SEC_TYPE 
J 2
(-5750 1300);
DISPLAY 0.680851 (-5750 1300);
DISPLAY INVISIBLE (-5750 1300);
FORCEPROP 1 LAST PATH I99
J 2
(-6000 750);
DISPLAY 0.723404 (-6000 750);
PAINT GREEN (-6000 750);
DISPLAY INVISIBLE (-6000 750);
FORCEPROP 1 LAST PART_NUMBER AL009617K02
J 2
(-5726 1110);
DISPLAY 0.723404 (-5726 1110);
PAINT GREEN (-5726 1110);
DISPLAY INVISIBLE (-5726 1110);
FORCEADD DNS..2
(-7825 2250);
PAINT RED (-7825 2250);
FORCEPROP 2 LAST CDS_LIB mstr_misc
J 0
(-7825 2250);
DISPLAY INVISIBLE (-7825 2250);
FORCEPROP 1 LAST COMMENT_BODY TRUE
J 0
(-7825 2250);
PAINT RED (-7825 2250);
DISPLAY INVISIBLE (-7825 2250);
FORCEADD DNS..2
(-7825 2400);
PAINT RED (-7825 2400);
FORCEPROP 2 LAST CDS_LIB mstr_misc
J 0
(-7825 2400);
DISPLAY INVISIBLE (-7825 2400);
FORCEPROP 1 LAST COMMENT_BODY TRUE
J 0
(-7825 2400);
PAINT RED (-7825 2400);
DISPLAY INVISIBLE (-7825 2400);
FORCEADD DNS..2
(-6000 3275);
PAINT RED (-6000 3275);
FORCEPROP 2 LAST CDS_LIB mstr_misc
J 0
(-6000 3275);
DISPLAY INVISIBLE (-6000 3275);
FORCEPROP 1 LAST COMMENT_BODY TRUE
J 0
(-6000 3275);
PAINT RED (-6000 3275);
DISPLAY INVISIBLE (-6000 3275);
FORCEADD DNS..2
(-6000 3375);
PAINT RED (-6000 3375);
FORCEPROP 2 LAST CDS_LIB mstr_misc
J 0
(-6000 3375);
DISPLAY INVISIBLE (-6000 3375);
FORCEPROP 1 LAST COMMENT_BODY TRUE
J 0
(-6000 3375);
PAINT RED (-6000 3375);
DISPLAY INVISIBLE (-6000 3375);
FORCEADD DNS..2
(-4100 2225);
PAINT RED (-4100 2225);
FORCEPROP 2 LAST CDS_LIB mstr_misc
J 0
(-4100 2225);
DISPLAY INVISIBLE (-4100 2225);
FORCEPROP 1 LAST COMMENT_BODY TRUE
J 0
(-4100 2225);
PAINT RED (-4100 2225);
DISPLAY INVISIBLE (-4100 2225);
FORCEADD CAD_NOTE..1
(-9075 1750);
FORCEPROP 0 LAST L1 R140/R151 R150/R162 CO-LAY
J 0
(-9225 1625);
DISPLAY 1.191489 (-9225 1625);
PAINT WHITE (-9225 1625);
FORCEPROP 2 LAST CDS_LIB pure_quanta_power
J 0
(-9075 1750);
DISPLAY INVISIBLE (-9075 1750);
FORCEPROP 1 LAST COMMENT_BODY TRUE
J 0
(-9050 1850);
DISPLAY 0.574468 (-9050 1850);
PAINT WHITE (-9050 1850);
DISPLAY INVISIBLE (-9050 1850);
FORCEADD CAD_NOTE..1
(-2800 1775);
FORCEPROP 0 LAST L1 R256/R274 R257/R281 CO-LAY
J 0
(-2950 1650);
DISPLAY 1.191489 (-2950 1650);
PAINT WHITE (-2950 1650);
FORCEPROP 2 LAST CDS_LIB pure_quanta_power
J 0
(-2800 1775);
DISPLAY INVISIBLE (-2800 1775);
FORCEPROP 1 LAST COMMENT_BODY TRUE
J 0
(-2775 1875);
DISPLAY 0.574468 (-2775 1875);
PAINT WHITE (-2775 1875);
DISPLAY INVISIBLE (-2775 1875);
FORCEADD QUANTA_TITLE_BLOCK_C..1
(-50 -3000);
FORCEPROP 0 LAST CDS_CON_LAST_MODIFIED Thu Sep 14 16:12:35 2023
J 0
(-1935 -2985);
DISPLAY INVISIBLE (-1935 -2985);
FORCEPROP 1 LAST CUSTOM_TXT_CDS <CON_LAST_MODIFIED>
J 0
(-1935 -2985);
DISPLAY 0.978723 (-1935 -2985);
FORCEPROP 2 LAST CUSTOM_TXT_CDS <XR_PAGE_TITLE>
J 0
(-7940 2250);
DISPLAY 0.638298 (-7940 2250);
PAINT PINK (-7940 2250);
DISPLAY INVISIBLE (-7940 2250);
FORCEPROP 1 LAST CUSTOM_TXT_CDS <NAME_2>
J 0
(-3225 -2950);
FORCEPROP 1 LAST CUSTOM_TXT_CDS <NAME_1>
J 0
(-3225 -2825);
FORCEPROP 1 LAST CUSTOM_TXT_CDS <Q_NUMBER>
J 0
(-1453 -2897);
DISPLAY 1.212766 (-1453 -2897);
FORCEPROP 1 LAST CUSTOM_TXT_CDS <Q_PROJ>
J 0
(-2432 -2898);
DISPLAY 1.212766 (-2432 -2898);
FORCEPROP 1 LAST CUSTOM_TXT_CDS <Q_REV>
J 0
(-234 -2897);
DISPLAY 1.212766 (-234 -2897);
FORCEPROP 1 LAST CUSTOM_TXT_CDS <CON_PAGE_NUM> OF <CON_TOTAL_PAGES>
J 0
(-496 -2982);
DISPLAY 0.978723 (-496 -2982);
FORCEPROP 1 LAST Q_TITLE I2C MUX - APML(1/2)
J 0
(-9350 -2950);
DISPLAY 2.446809 (-9350 -2950);
PAINT GREEN (-9350 -2950);
FORCEPROP 2 LAST PAGE_BORDER TRUE
J 0
(-7940 2250);
DISPLAY 0.638298 (-7940 2250);
PAINT PINK (-7940 2250);
DISPLAY INVISIBLE (-7940 2250);
FORCEPROP 1 LAST CDS_LMAN_SYM_OUTLINE -9475,6775,100,-125
J 0
(-50 -3000);
DISPLAY 0.468085 (-50 -3000);
PAINT GREEN (-50 -3000);
DISPLAY INVISIBLE (-50 -3000);
FORCEPROP 2 LAST CDS_LIB pure_quanta
J 0
(-50 -3000);
DISPLAY INVISIBLE (-50 -3000);
FORCEPROP 2 LAST CDS_XR_PAGE_TITLE CR-160 : @T6G_MB_LIB.T6G(SCH_1):PAGE160
J 0
(-7940 2250);
DISPLAY 0.638298 (-7940 2250);
PAINT PINK (-7940 2250);
DISPLAY INVISIBLE (-7940 2250);
FORCEPROP 1 LAST Q_DEPT BU9
J 1
(-3813 -2951);
DISPLAY 1.957447 (-3813 -2951);
PAINT GREEN (-3813 -2951);
DISPLAY INVISIBLE (-3813 -2951);
FORCEPROP 1 LAST COMMENT_BODY TRUE
J 0
(-38 -3013);
DISPLAY 0.978723 (-38 -3013);
PAINT GREEN (-38 -3013);
DISPLAY INVISIBLE (-38 -3013);
FORCEADD DNS..2
(-6800 -2250);
PAINT RED (-6800 -2250);
FORCEPROP 2 LAST CDS_LIB mstr_misc
J 0
(-6800 -2250);
DISPLAY INVISIBLE (-6800 -2250);
FORCEPROP 1 LAST COMMENT_BODY TRUE
J 0
(-6800 -2250);
PAINT RED (-6800 -2250);
DISPLAY INVISIBLE (-6800 -2250);
FORCEADD DNS..2
(-7025 125);
PAINT RED (-7025 125);
FORCEPROP 2 LAST CDS_LIB mstr_misc
J 0
(-7025 125);
DISPLAY INVISIBLE (-7025 125);
FORCEPROP 1 LAST COMMENT_BODY TRUE
J 0
(-7025 125);
PAINT RED (-7025 125);
DISPLAY INVISIBLE (-7025 125);
FORCEADD DNS..2
(-6025 2325);
PAINT RED (-6025 2325);
FORCEPROP 2 LAST CDS_LIB mstr_misc
J 0
(-6025 2325);
DISPLAY INVISIBLE (-6025 2325);
FORCEPROP 1 LAST COMMENT_BODY TRUE
J 0
(-6025 2325);
PAINT RED (-6025 2325);
DISPLAY INVISIBLE (-6025 2325);
FORCEADD DNS..2
(-625 -175);
PAINT RED (-625 -175);
FORCEPROP 2 LAST CDS_LIB mstr_misc
J 0
(-625 -175);
DISPLAY INVISIBLE (-625 -175);
FORCEPROP 1 LAST COMMENT_BODY TRUE
J 0
(-625 -175);
PAINT RED (-625 -175);
DISPLAY INVISIBLE (-625 -175);
FORCEADD DNS..2
(-900 -175);
PAINT RED (-900 -175);
FORCEPROP 2 LAST CDS_LIB mstr_misc
J 0
(-900 -175);
DISPLAY INVISIBLE (-900 -175);
FORCEPROP 1 LAST COMMENT_BODY TRUE
J 0
(-900 -175);
PAINT RED (-900 -175);
DISPLAY INVISIBLE (-900 -175);
FORCEADD DNS..2
(-1200 -175);
PAINT RED (-1200 -175);
FORCEPROP 2 LAST CDS_LIB mstr_misc
J 0
(-1200 -175);
DISPLAY INVISIBLE (-1200 -175);
FORCEPROP 1 LAST COMMENT_BODY TRUE
J 0
(-1200 -175);
PAINT RED (-1200 -175);
DISPLAY INVISIBLE (-1200 -175);
FORCEADD DNS..2
(-1500 -175);
PAINT RED (-1500 -175);
FORCEPROP 2 LAST CDS_LIB mstr_misc
J 0
(-1500 -175);
DISPLAY INVISIBLE (-1500 -175);
FORCEPROP 1 LAST COMMENT_BODY TRUE
J 0
(-1500 -175);
PAINT RED (-1500 -175);
DISPLAY INVISIBLE (-1500 -175);
FORCEADD DNS..2
(-1675 -150);
PAINT RED (-1675 -150);
FORCEPROP 2 LAST CDS_LIB mstr_misc
J 0
(-1675 -150);
DISPLAY INVISIBLE (-1675 -150);
FORCEPROP 1 LAST COMMENT_BODY TRUE
J 0
(-1675 -150);
PAINT RED (-1675 -150);
DISPLAY INVISIBLE (-1675 -150);
FORCEADD DNS..2
(-1950 -75);
PAINT RED (-1950 -75);
FORCEPROP 2 LAST CDS_LIB mstr_misc
J 0
(-1950 -75);
DISPLAY INVISIBLE (-1950 -75);
FORCEPROP 1 LAST COMMENT_BODY TRUE
J 0
(-1950 -75);
PAINT RED (-1950 -75);
DISPLAY INVISIBLE (-1950 -75);
FORCEADD DNS..2
(-2700 2375);
PAINT RED (-2700 2375);
FORCEPROP 2 LAST CDS_LIB mstr_misc
J 0
(-2700 2375);
DISPLAY INVISIBLE (-2700 2375);
FORCEPROP 1 LAST COMMENT_BODY TRUE
J 0
(-2700 2375);
PAINT RED (-2700 2375);
DISPLAY INVISIBLE (-2700 2375);
FORCEADD DNS..2
(-4200 1775);
PAINT RED (-4200 1775);
FORCEPROP 2 LAST CDS_LIB mstr_misc
J 0
(-4200 1775);
DISPLAY INVISIBLE (-4200 1775);
FORCEPROP 1 LAST COMMENT_BODY TRUE
J 0
(-4200 1775);
PAINT RED (-4200 1775);
DISPLAY INVISIBLE (-4200 1775);
FORCEADD DNS..2
(-2700 2200);
PAINT RED (-2700 2200);
FORCEPROP 2 LAST CDS_LIB mstr_misc
J 0
(-2700 2200);
DISPLAY INVISIBLE (-2700 2200);
FORCEPROP 1 LAST COMMENT_BODY TRUE
J 0
(-2700 2200);
PAINT RED (-2700 2200);
DISPLAY INVISIBLE (-2700 2200);
FORCEADD DNS..2
(-4100 2325);
PAINT RED (-4100 2325);
FORCEPROP 2 LAST CDS_LIB mstr_misc
J 0
(-4100 2325);
DISPLAY INVISIBLE (-4100 2325);
FORCEPROP 1 LAST COMMENT_BODY TRUE
J 0
(-4100 2325);
PAINT RED (-4100 2325);
DISPLAY INVISIBLE (-4100 2325);
WIRE 16 -1 (-6400 2100)(-6500 2100);
WIRE 16 -1 (-6500 2100)(-6500 1975);
WIRE 16 -1 (-6650 2650)(-6650 2600);
WIRE 16 -1 (-5325 2650)(-5325 2600);
WIRE 16 -1 (-5350 -1825)(-5050 -1825);
WIRE 16 -1 (-5050 -1825)(-5050 -2025);
WIRE 16 -1 (-4225 1875)(-4225 2000);
WIRE 16 -1 (-1550 50)(-1550 -50);
WIRE 16 -1 (-1225 50)(-1225 -50);
WIRE 16 -1 (-925 50)(-925 -50);
WIRE 16 -1 (-650 125)(-650 -50);
WIRE 16 -1 (-6450 -1275)(-6450 -1325);
WIRE 16 -1 (-6825 -2150)(-6825 -2025);
WIRE 16 -1 (-5275 1050)(-5275 1000);
WIRE 16 -1 (-6675 1100)(-6675 1050);
WIRE 16 -1 (-5575 550)(-5400 550);
WIRE 16 -1 (-5400 550)(-5400 425);
WIRE 16 -1 (-7050 225)(-7050 350);
WIRE 16 -1 (-1750 -50)(-1750 25);
WIRE 16 -1 (-2000 0)(-2000 75);
WIRE 16 -1 (-5125 -1275)(-5125 -1325);
WIRE 16 -1 (-5575 800)(-4500 800);
FORCEPROP 2 LAST SIG_NAME SMB_CPU0_CPU1_APML_BUF2_SCL_R1
J 0
(-5510 810);
DISPLAY 0.510638 (-5510 810);
PAINT WHITE (-5510 810);
FORCEPROP 2 LASTPROP $XRERR UNIQUE?
J 0
(-5750 810);
DISPLAY 0.638298 (-5750 810);
PAINT MONO (-5750 810);
DISPLAY INVISIBLE (-5750 810);
WIRE 16 -1 (-5575 700)(-4475 700);
FORCEPROP 2 LAST SIG_NAME SMB_CPU0_CPU1_APML_BUF2_SDA_R1
J 0
(-5510 710);
DISPLAY 0.510638 (-5510 710);
PAINT WHITE (-5510 710);
FORCEPROP 2 LASTPROP $XRERR UNIQUE?
J 0
(-5750 710);
DISPLAY 0.638298 (-5750 710);
PAINT MONO (-5750 710);
DISPLAY INVISIBLE (-5750 710);
WIRE 16 -1 (-5350 1325)(-5350 1250);
WIRE 16 -1 (-5275 1250)(-5350 1250);
WIRE 16 -1 (-5350 1250)(-5350 950);
WIRE 16 -1 (-5350 950)(-5575 950);
WIRE 16 -1 (-7850 800)(-8775 800);
FORCEPROP 2 LAST SIG_NAME SMB_CPU0_CPU1_APML_SCL
J 0
(-8660 835);
DISPLAY 0.510638 (-8660 835);
PAINT WHITE (-8660 835);
WIRE 16 -1 (-1550 -250)(-1550 -450);
WIRE 16 -1 (-2425 -450)(-1550 -450);
FORCEPROP 2 LAST SIG_NAME SMB_CPU0_CPU1_APML_BUF1_SCL_R2
J 0
(-2285 -440);
DISPLAY 0.510638 (-2285 -440);
PAINT WHITE (-2285 -440);
WIRE 16 -1 (-650 -250)(-650 -600);
WIRE 16 -1 (-2425 -600)(-650 -600);
FORCEPROP 2 LAST SIG_NAME SMB_CPU0_CPU1_SEC_SDA_R2
J 0
(-2285 -590);
DISPLAY 0.510638 (-2285 -590);
PAINT WHITE (-2285 -590);
WIRE 16 -1 (-925 -250)(-925 -550);
WIRE 16 -1 (-2425 -550)(-925 -550);
FORCEPROP 2 LAST SIG_NAME SMB_CPU0_CPU1_SEC_SCL_R2
J 0
(-2285 -540);
DISPLAY 0.510638 (-2285 -540);
PAINT WHITE (-2285 -540);
WIRE 16 -1 (-1225 -250)(-1225 -500);
WIRE 16 -1 (-2425 -500)(-1225 -500);
FORCEPROP 2 LAST SIG_NAME SMB_CPU0_CPU1_APML_BUF1_SDA_R2
J 0
(-2285 -490);
DISPLAY 0.510638 (-2285 -490);
PAINT WHITE (-2285 -490);
WIRE 16 -1 (-6200 -1675)(-7675 -1675);
FORCEPROP 2 LAST SIG_NAME SMB_CPU0_CPU1_SEC_SDA
J 0
(-7635 -1665);
DISPLAY 0.510638 (-7635 -1665);
PAINT WHITE (-7635 -1665);
WIRE 16 -1 (-6350 -1825)(-6350 -2500);
WIRE 16 -1 (-6200 -1825)(-6350 -1825);
WIRE 16 -1 (-6350 -2500)(-6825 -2500);
FORCEPROP 2 LAST SIG_NAME PU_U96_EN
J 0
(-6710 -2475);
DISPLAY 0.489362 (-6710 -2475);
FORCEPROP 2 LASTPROP $XRERR UNIQUE?
J 0
(-6950 -2475);
DISPLAY 0.638298 (-6950 -2475);
PAINT MONO (-6950 -2475);
DISPLAY INVISIBLE (-6950 -2475);
WIRE 16 -1 (-6825 -2500)(-6825 -2350);
WIRE 16 -1 (-6200 -1575)(-7725 -1575);
FORCEPROP 2 LAST SIG_NAME SMB_CPU0_CPU1_SEC_SCL
J 0
(-7635 -1565);
DISPLAY 0.510638 (-7635 -1565);
PAINT WHITE (-7635 -1565);
WIRE 16 -1 (-3800 -1675)(-2975 -1675);
FORCEPROP 2 LAST SIG_NAME SMB_CPU0_CPU1_SEC_SDA_R2
J 0
(-3560 -1665);
DISPLAY 0.510638 (-3560 -1665);
PAINT WHITE (-3560 -1665);
WIRE 16 -1 (-3800 -1575)(-2950 -1575);
FORCEPROP 2 LAST SIG_NAME SMB_CPU0_CPU1_SEC_SCL_R2
J 0
(-3560 -1565);
DISPLAY 0.510638 (-3560 -1565);
PAINT WHITE (-3560 -1565);
WIRE 16 -1 (-5350 -1675)(-4000 -1675);
FORCEPROP 2 LAST SIG_NAME SMB_CPU0_CPU1_SEC_SDA_R1
J 0
(-5035 -1665);
DISPLAY 0.510638 (-5035 -1665);
PAINT WHITE (-5035 -1665);
FORCEPROP 2 LASTPROP $XRERR UNIQUE?
J 0
(-5275 -1665);
DISPLAY 0.638298 (-5275 -1665);
PAINT MONO (-5275 -1665);
DISPLAY INVISIBLE (-5275 -1665);
WIRE 16 -1 (-5350 -1575)(-4000 -1575);
FORCEPROP 2 LAST SIG_NAME SMB_CPU0_CPU1_SEC_SCL_R1
J 0
(-5035 -1565);
DISPLAY 0.510638 (-5035 -1565);
PAINT WHITE (-5035 -1565);
FORCEPROP 2 LASTPROP $XRERR UNIQUE?
J 0
(-5275 -1565);
DISPLAY 0.638298 (-5275 -1565);
PAINT MONO (-5275 -1565);
DISPLAY INVISIBLE (-5275 -1565);
WIRE 16 -1 (-7950 2350)(-8700 2350);
FORCEPROP 2 LAST SIG_NAME SMB_CPU0_CPU1_APML_SCL
J 0
(-8660 2385);
DISPLAY 0.510638 (-8660 2385);
PAINT WHITE (-8660 2385);
WIRE 16 -1 (-2825 2250)(-2975 2250);
WIRE 16 -1 (-2975 2075)(-2975 2250);
WIRE 16 -1 (-2975 2250)(-4000 2250);
FORCEPROP 2 LAST SIG_NAME SMB_CPU0_CPU1_APML_BUF1_SDA_R2
J 0
(-3885 2285);
DISPLAY 0.638298 (-3885 2285);
PAINT WHITE (-3885 2285);
WIRE 16 -1 (-3150 2075)(-2975 2075);
WIRE 16 -1 (-2975 2700)(-2975 2350);
WIRE 16 -1 (-3175 2700)(-2975 2700);
WIRE 16 -1 (-2850 2350)(-2975 2350);
WIRE 16 -1 (-2975 2350)(-4000 2350);
FORCEPROP 2 LAST SIG_NAME SMB_CPU0_CPU1_APML_BUF1_SCL_R2
J 0
(-3885 2360);
DISPLAY 0.638298 (-3885 2360);
PAINT WHITE (-3885 2360);
WIRE 16 -1 (-6075 3325)(-7225 3325);
WIRE 16 -1 (-7225 2250)(-7225 3325);
WIRE 16 -1 (-7225 2250)(-6400 2250);
WIRE 16 -1 (-7750 2250)(-7225 2250);
FORCEPROP 2 LAST SIG_NAME SMB_CPU0_CPU1_APML_BUF1_SDA
J 0
(-7185 2260);
DISPLAY 0.510638 (-7185 2260);
PAINT WHITE (-7185 2260);
FORCEPROP 2 LASTPROP $XRERR UNIQUE?
J 0
(-7425 2260);
DISPLAY 0.638298 (-7425 2260);
PAINT MONO (-7425 2260);
DISPLAY INVISIBLE (-7425 2260);
WIRE 16 -1 (-6075 3375)(-7300 3375);
WIRE 16 -1 (-7300 2350)(-7300 3375);
WIRE 16 -1 (-7300 2350)(-6400 2350);
WIRE 16 -1 (-7750 2350)(-7300 2350);
FORCEPROP 2 LAST SIG_NAME SMB_CPU0_CPU1_APML_BUF1_SCL
J 0
(-7185 2385);
DISPLAY 0.510638 (-7185 2385);
PAINT WHITE (-7185 2385);
FORCEPROP 2 LASTPROP $XRERR UNIQUE?
J 0
(-7425 2385);
DISPLAY 0.638298 (-7425 2385);
PAINT MONO (-7425 2385);
DISPLAY INVISIBLE (-7425 2385);
WIRE 16 -1 (-5875 3375)(-4350 3375);
WIRE 16 -1 (-4350 2350)(-4350 3375);
WIRE 16 -1 (-4350 2350)(-4200 2350);
WIRE 16 -1 (-5550 2350)(-4350 2350);
FORCEPROP 2 LAST SIG_NAME SMB_CPU0_CPU1_APML_BUF1_SCL_R1
J 0
(-5260 2360);
DISPLAY 0.510638 (-5260 2360);
PAINT WHITE (-5260 2360);
FORCEPROP 2 LASTPROP $XRERR UNIQUE?
J 0
(-5500 2360);
DISPLAY 0.638298 (-5500 2360);
PAINT MONO (-5500 2360);
DISPLAY INVISIBLE (-5500 2360);
WIRE 16 -1 (-5875 3325)(-4425 3325);
WIRE 16 -1 (-4425 2250)(-4425 3325);
WIRE 16 -1 (-4425 2250)(-4200 2250);
WIRE 16 -1 (-5550 2250)(-4425 2250);
FORCEPROP 2 LAST SIG_NAME SMB_CPU0_CPU1_APML_BUF1_SDA_R1
J 0
(-5260 2260);
DISPLAY 0.510638 (-5260 2260);
PAINT WHITE (-5260 2260);
FORCEPROP 2 LASTPROP $XRERR UNIQUE?
J 0
(-5500 2260);
DISPLAY 0.638298 (-5500 2260);
PAINT MONO (-5500 2260);
DISPLAY INVISIBLE (-5500 2260);
WIRE 16 -1 (-4225 1600)(-4225 1675);
WIRE 16 -1 (-4725 1600)(-4225 1600);
WIRE 16 -1 (-4725 2100)(-4725 1600);
WIRE 16 -1 (-4725 2100)(-5550 2100);
FORCEPROP 2 LAST SIG_NAME PU_U5_EN
J 0
(-5385 2110);
DISPLAY 0.489362 (-5385 2110);
FORCEPROP 2 LASTPROP $XRERR UNIQUE?
J 0
(-5625 2110);
DISPLAY 0.638298 (-5625 2110);
PAINT MONO (-5625 2110);
DISPLAY INVISIBLE (-5625 2110);
WIRE 16 -1 (-7850 700)(-8775 700);
FORCEPROP 2 LAST SIG_NAME SMB_CPU0_CPU1_APML_SDA
J 0
(-8685 735);
DISPLAY 0.510638 (-8685 735);
PAINT WHITE (-8685 735);
WIRE 16 -1 (-7950 2250)(-8700 2250);
FORCEPROP 2 LAST SIG_NAME SMB_CPU0_CPU1_APML_SDA
J 0
(-8660 2285);
DISPLAY 0.510638 (-8660 2285);
PAINT WHITE (-8660 2285);
WIRE 16 -1 (-7650 800)(-6425 800);
FORCEPROP 2 LAST SIG_NAME SMB_CPU0_CPU1_APML_BUF2_SCL
J 0
(-7210 810);
DISPLAY 0.510638 (-7210 810);
PAINT WHITE (-7210 810);
FORCEPROP 2 LASTPROP $XRERR UNIQUE?
J 0
(-7450 810);
DISPLAY 0.638298 (-7450 810);
PAINT MONO (-7450 810);
DISPLAY INVISIBLE (-7450 810);
WIRE 16 -1 (-6425 700)(-7650 700);
FORCEPROP 2 LAST SIG_NAME SMB_CPU0_CPU1_APML_BUF2_SDA
J 0
(-7185 710);
DISPLAY 0.510638 (-7185 710);
PAINT WHITE (-7185 710);
FORCEPROP 2 LASTPROP $XRERR UNIQUE?
J 0
(-7425 710);
DISPLAY 0.638298 (-7425 710);
PAINT MONO (-7425 710);
DISPLAY INVISIBLE (-7425 710);
WIRE 16 -1 (-7050 -125)(-7050 25);
WIRE 16 -1 (-6575 -125)(-7050 -125);
FORCEPROP 2 LAST SIG_NAME PU_U2_EN
J 0
(-6935 -115);
DISPLAY 0.489362 (-6935 -115);
FORCEPROP 2 LASTPROP $XRERR UNIQUE?
J 0
(-7175 -115);
DISPLAY 0.638298 (-7175 -115);
PAINT MONO (-7175 -115);
DISPLAY INVISIBLE (-7175 -115);
WIRE 16 -1 (-6575 550)(-6575 -125);
WIRE 16 -1 (-6425 550)(-6575 550);
WIRE 16 -1 (-2000 -200)(-2000 -350);
WIRE 16 -1 (-2000 -350)(-2425 -350);
FORCEPROP 2 LAST SIG_NAME SMB_CPU0_CPU1_APML_BUF2_SDA_R2
J 0
(-2410 -340);
DISPLAY 0.404255 (-2410 -340);
PAINT WHITE (-2410 -340);
WIRE 16 -1 (-1750 -250)(-1750 -400);
WIRE 16 -1 (-1750 -400)(-2425 -400);
FORCEPROP 2 LAST SIG_NAME SMB_CPU0_CPU1_APML_BUF2_SCL_R2
J 0
(-2410 -390);
DISPLAY 0.404255 (-2410 -390);
PAINT WHITE (-2410 -390);
WIRE 16 -1 (-2650 2350)(-1400 2350);
FORCEPROP 2 LAST SIG_NAME SMB_CPU0_CPU1_APML_SCL_R2
J 0
(-2210 2385);
DISPLAY 0.638298 (-2210 2385);
PAINT WHITE (-2210 2385);
WIRE 16 -1 (-2700 1075)(-2800 1075);
WIRE 16 -1 (-2700 800)(-2700 1075);
WIRE 16 -1 (-2700 800)(-2450 800);
WIRE 16 -1 (-4300 800)(-2700 800);
FORCEPROP 2 LAST SIG_NAME SMB_CPU0_CPU1_APML_BUF2_SCL_R2
J 0
(-3685 835);
DISPLAY 0.638298 (-3685 835);
PAINT WHITE (-3685 835);
WIRE 16 -1 (-2250 800)(-750 800);
FORCEPROP 2 LAST SIG_NAME SMB_CPU0_CPU1_APML_SCL_R2
J 0
(-1610 835);
DISPLAY 0.638298 (-1610 835);
PAINT WHITE (-1610 835);
WIRE 16 -1 (-2625 2250)(-1425 2250);
FORCEPROP 2 LAST SIG_NAME SMB_CPU0_CPU1_APML_SDA_R2
J 0
(-2210 2285);
DISPLAY 0.638298 (-2210 2285);
PAINT WHITE (-2210 2285);
WIRE 16 -1 (-4275 700)(-2700 700);
FORCEPROP 2 LAST SIG_NAME SMB_CPU0_CPU1_APML_BUF2_SDA_R2
J 0
(-3685 710);
DISPLAY 0.638298 (-3685 710);
PAINT WHITE (-3685 710);
WIRE 16 -1 (-2700 700)(-2425 700);
WIRE 16 -1 (-2700 475)(-2700 700);
WIRE 16 -1 (-2825 475)(-2700 475);
WIRE 16 -1 (-2225 700)(-775 700);
FORCEPROP 2 LAST SIG_NAME SMB_CPU0_CPU1_APML_SDA_R2
J 0
(-1585 710);
DISPLAY 0.638298 (-1585 710);
PAINT WHITE (-1585 710);
WIRE 16 -1 (-6450 -1075)(-6450 -1000);
WIRE 16 -1 (-6450 -1000)(-6275 -1000);
WIRE 16 -1 (-6275 -950)(-6275 -1000);
WIRE 16 -1 (-6275 -1425)(-6275 -1000);
WIRE 16 -1 (-6200 -1425)(-6275 -1425);
WIRE 16 -1 (-6425 950)(-6500 950);
WIRE 16 -1 (-6500 950)(-6500 1375);
WIRE 16 -1 (-6500 1425)(-6500 1375);
WIRE 16 -1 (-6675 1375)(-6500 1375);
WIRE 16 -1 (-6675 1300)(-6675 1375);
WIRE 16 -1 (-5350 -1425)(-5200 -1425);
WIRE 16 -1 (-5200 -1075)(-5200 -1425);
WIRE 16 -1 (-5200 -975)(-5200 -1075);
WIRE 16 -1 (-5125 -1075)(-5200 -1075);
WIRE 16 -1 (-5550 2500)(-5400 2500);
WIRE 16 -1 (-5400 2850)(-5400 2500);
WIRE 16 -1 (-5325 2850)(-5400 2850);
WIRE 16 -1 (-5400 2950)(-5400 2850);
WIRE 16 -1 (-6650 2850)(-6650 2925);
WIRE 16 -1 (-6650 2925)(-6475 2925);
WIRE 16 -1 (-6475 2975)(-6475 2925);
WIRE 16 -1 (-6475 2500)(-6475 2925);
WIRE 16 -1 (-6400 2500)(-6475 2500);
DOT 1 (-2700 700);
DOT 1 (-5400 2850);
DOT 1 (-5350 1250);
DOT 1 (-2700 800);
DOT 1 (-6500 1375);
DOT 1 (-6475 2925);
DOT 1 (-5200 -1075);
CIRCLE (-4550 -1975)(-4335 -1975);
PAINT YELLOW (-4550 -1975);
DOT 1 (-6275 -1000);
DOT 1 (-4425 2250);
DOT 1 (-2975 2350);
DOT 1 (-2975 2250);
DOT 1 (-7225 2250);
DOT 1 (-7300 2350);
DOT 1 (-4350 2350);
FORCENOTE
INTERNAL PU
(-6025 -2025) 0;
DISPLAY LEFT (-6025 -2025);
DISPLAY 1.021277 (-6025 -2025);
FORCENOTE
TBC
(-4650 -2025) 0;
DISPLAY LEFT (-4650 -2025);
DISPLAY 1.595745 (-4650 -2025);
FORCENOTE
FROM MAIN SOURCE MUX
(-2600 2525) 0;
DISPLAY LEFT (-2600 2525);
DISPLAY 2.000000 (-2600 2525);
FORCENOTE
FROM 2ND SOURCE MUX
(-2175 1000) 0;
DISPLAY LEFT (-2175 1000);
DISPLAY 2.000000 (-2175 1000);
FORCENOTE
INTERNAL PU
(-6200 1875) 0;
DISPLAY LEFT (-6200 1875);
DISPLAY 1.021277 (-6200 1875);
QUIT
